G04 ================== begin FILE IDENTIFICATION RECORD ==================*
G04 Layout Name:  DAT6MTH3AD0_t6m_cm_d_brd_103112_274.brd*
G04 Film Name:    in3*
G04 File Format:  Gerber RS274X*
G04 File Origin:  Cadence Allegro 16.3-S048*
G04 Origin Date:  Tue Nov 26 10:18:24 2013*
G04 *
G04 Layer:  VIA CLASS/IN3*
G04 Layer:  PIN/IN3*
G04 Layer:  MANUFACTURING/PHOTOPLOT_OUTLINE*
G04 Layer:  ETCH/IN3*
G04 Layer:  DRAWING FORMAT/TITLE_BLOCK*
G04 Layer:  DRAWING FORMAT/TITLE_DATA_IN3*
G04 *
G04 Offset:    (0.00 0.00)*
G04 Mirror:    No*
G04 Mode:      Positive*
G04 Rotation:  0*
G04 FullContactRelief:  No*
G04 UndefLineWidth:     6.00*
G04 ================== end FILE IDENTIFICATION RECORD ====================*
%FSLAX25Y25*MOIN*%
%IR0*IPPOS*OFA0.00000B0.00000*MIA0B0*SFA1.00000B1.00000*%
%ADD10C,.02*%
%ADD15C,.052*%
%ADD14C,.061*%
%ADD12C,.045*%
%ADD16C,.058*%
%ADD13C,.0193*%
%ADD11C,.077*%
%ADD17C,.01*%
%ADD18C,.04*%
%ADD19C,.015*%
%ADD20C,.004*%
%ADD21C,.0041*%
%ADD22C,.006*%
%ADD23C,.005*%
%ADD24C,.008*%
%ADD25C,.0045*%
%ADD26C,.0039*%
%ADD27C,.0067*%
%ADD32O,.05002X.14502*%
%ADD30C,.03004*%
%ADD31C,.03006*%
%ADD40C,.05204*%
%ADD41C,.06204*%
%ADD38C,.07104*%
%ADD35C,.02804*%
%ADD36C,.02734*%
%ADD37C,.07604*%
%ADD33C,.09107*%
%ADD42C,.06804*%
%ADD39C,.08604*%
%ADD34C,.02934*%
%ADD29C,.08704*%
%ADD43C,.15004*%
%ADD28C,.15206*%
G75*
%LPD*%
G75*
G36*
G01X7246Y376095D02*
X10270Y379119D01*
X50230D01*
X54480Y374869D01*
Y314318D01*
X51956Y311794D01*
G02X51603Y311647I-354J353D01*
G01X11331D01*
X7246Y315732D01*
Y376095D01*
G37*
G36*
G01X6970Y380508D02*
G02X6470Y381008I0J500D01*
G01Y660124D01*
X9160Y662814D01*
X41629D01*
X55020Y676205D01*
Y787211D01*
G02X56200Y788195I1000J0D01*
G03Y791139I300J1472D01*
G02X55020Y792123I-180J984D01*
G01Y793055D01*
X58239Y796274D01*
X185239D01*
X197640Y783873D01*
Y736442D01*
X197590Y736338D01*
G03X197574Y736305I1343J-672D01*
G01X197571Y736300D01*
Y736299D01*
X197568Y736292D01*
G03Y735070I1372J-611D01*
G01X197571Y735063D01*
Y735062D01*
X197574Y735057D01*
G03X197590Y735024I1359J639D01*
G01X197640Y734920D01*
Y726381D01*
G02X196416Y725407I-1000J0D01*
G03X194674Y724475I-337J-1464D01*
G02X193691Y723830I-935J354D01*
G03X193568Y723835I-122J-1497D01*
G03X193553I-8J-1502D01*
G02X192593Y724526I-9J1000D01*
G03X190169Y725245I-1443J-418D01*
G03X189715Y724552I981J-1138D01*
G02X188707Y723848I-956J295D01*
G03X188563Y723855I-145J-1495D01*
G01X188562D01*
G02X187607Y724551I-2J1000D01*
G03X186358Y725623I-1443J-417D01*
G03X184724Y724562I-194J-1489D01*
G02X183701Y723849I-959J285D01*
G03X182315Y721521I-135J-1496D01*
G03X185006Y721925I1251J832D01*
G02X186029Y722638I959J-285D01*
G03X186165Y722632I134J1496D01*
G03X186168I1J1502D01*
G02X187123Y721936I2J-1000D01*
G03X189291Y721038I1443J417D01*
G03X190001Y721909I-725J1316D01*
G02X191009Y722613I956J-295D01*
G03X191150Y722606I145J1495D01*
G03X191163I7J1502D01*
G02X192123Y721915I9J-1000D01*
G03X193387Y720842I1443J418D01*
G03X194971Y721801I180J1491D01*
G02X195954Y722446I935J-354D01*
G03X196184Y722445I122J1497D01*
G02X197166Y721808I50J-999D01*
G03X197431Y721369I1400J545D01*
G03X197496Y721299I1133J987D01*
G02X197640Y720948I-356J-351D01*
G01Y715054D01*
G02X196454Y714072I-1000J0D01*
G03Y711132I-310J-1470D01*
G02X197640Y710150I186J-982D01*
G01Y705427D01*
G02X197251Y704939I-500J0D01*
G01X197250D01*
G03X197015Y704865I332J-1465D01*
G02X195791Y705258I-378J926D01*
G03X193097Y704990I-1283J-782D01*
G03X195075Y703085I1411J-514D01*
G02X196299Y702692I378J-926D01*
G03X196534Y702398I1282J784D01*
G03X197250Y702009I1048J1076D01*
G01X197251D01*
G02X197640Y701521I-111J-488D01*
G01Y699898D01*
G02X197166Y699399I-500J0D01*
G03Y696399I77J-1500D01*
G02X197640Y695900I-26J-499D01*
G01Y694316D01*
X192908Y689584D01*
X192304D01*
G02X192120Y690539I25J500D01*
G03X193040Y691817I-578J1386D01*
G03X192097Y693321I-1498J108D01*
G02X191624Y694789I369J929D01*
G03X190011Y697081I-1249J835D01*
G03X189820Y694228I364J-1457D01*
G02X190293Y692760I-369J-929D01*
G03X190099Y691509I1249J-834D01*
G03X190807Y690615I1443J416D01*
G02X191024Y689036I-490J-872D01*
G01X186164Y684176D01*
X185963Y684172D01*
G03X184491Y682700I30J-1502D01*
G01X184487Y682499D01*
X178566Y676578D01*
X178496Y676542D01*
G03X177843Y675889I684J-1337D01*
G01X177807Y675819D01*
X170676Y668688D01*
G02X169112Y668880I-707J707D01*
G03X167061Y666829I-1302J-749D01*
G02X167253Y665265I-515J-857D01*
G01X166023Y664035D01*
G02X165455Y663936I-354J353D01*
G03X163455Y661936I-643J-1357D01*
G01X163523Y661792D01*
X163468Y661480D01*
X163356Y661368D01*
X163126Y661138D01*
X157208D01*
Y655220D01*
X87910Y585922D01*
G02X86389Y586048I-707J707D01*
G03X83639Y585149I-1249J-835D01*
G02X82796Y584140I-1000J-22D01*
G03X81775Y583481I234J-1483D01*
G03X82049Y581519I1255J-825D01*
G02X82071Y580083I-685J-729D01*
G01X81398Y579410D01*
X81245Y579382D01*
G03X80039Y578176I271J-1477D01*
G01X80011Y578023D01*
X68831Y566843D01*
G02X67241Y567080I-707J707D01*
G03X64662Y567254I-1341J-677D01*
G03X65744Y564909I1238J-851D01*
G01X65921Y564891D01*
X66046Y564765D01*
G02Y564058I-354J-353D01*
G01X65451Y563463D01*
X65400Y563432D01*
G03X64898Y562930I781J-1283D01*
G01X64867Y562879D01*
X63651Y561663D01*
X63525Y561627D01*
G03X62484Y560586I405J-1446D01*
G01X62448Y560460D01*
X53046Y551058D01*
G02X51469Y551271I-707J707D01*
G03X49441Y549243I-1329J-699D01*
G02X49654Y547666I-494J-870D01*
G01X45113Y543125D01*
G02X43431Y543610I-707J707D01*
G03X41573Y544773I-1474J-289D01*
G03X41092Y544549I384J-1452D01*
G02X39833Y544636I-576J817D01*
G03X38558Y545020I-1026J-1097D01*
G03X37402Y544069I249J-1481D01*
G03X39672Y542311I1405J-530D01*
G02X40931Y542224I576J-817D01*
G03X40984Y542177I1023J1100D01*
G03X41668Y541847I973J1144D01*
G02X42153Y540165I-222J-975D01*
G01X41747Y539759D01*
G02X40441Y539666I-707J707D01*
G03X38338Y537563I-901J-1202D01*
G02X38245Y536257I-800J-599D01*
G01X29030Y527042D01*
Y474568D01*
G02X28133Y473573I-1000J0D01*
G03Y470579I117J-1497D01*
G02X29030Y469584I-103J-995D01*
G01Y441232D01*
G02X28133Y440237I-1000J0D01*
G03Y437243I117J-1497D01*
G02X29030Y436248I-103J-995D01*
G01Y411195D01*
X29400D01*
X40789Y399806D01*
X48115D01*
X48401Y399663D01*
X52180Y395884D01*
X53740Y394092D01*
X54239Y392829D01*
X54404Y391816D01*
X54420Y391715D01*
Y381008D01*
G02X53920Y380508I-500J0D01*
G01X6970D01*
G37*
G36*
G01X81249Y156155D02*
G02X80289Y157434I0J1000D01*
G03X77416Y158314I-1439J432D01*
G02X76309Y157628I-953J302D01*
G03X74747Y156933I-279J-1476D01*
G03X74616Y156659I1283J-782D01*
G01X74567Y156522D01*
X74092Y156155D01*
X43388D01*
X43134Y156328D01*
X43077Y156472D01*
G03X38874Y157214I-2328J-914D01*
G01X38531Y157557D01*
X38366Y157722D01*
X36500Y159589D01*
Y178287D01*
X36694Y178551D01*
X36850Y178600D01*
G03X38772Y181079I-826J2625D01*
G03X37659Y183439I-2748J146D01*
G02Y185019I613J790D01*
G03Y189447I-1635J2214D01*
G02Y191027I613J790D01*
G03Y195455I-1635J2214D01*
G02Y197035I613J790D01*
G03X37525Y201556I-1635J2214D01*
G01X37481Y201585D01*
X36075Y202991D01*
X34548D01*
X33677Y203862D01*
Y206824D01*
X34473Y207620D01*
X36500D01*
Y208326D01*
X36694Y208590D01*
X36850Y208639D01*
G03X38772Y211118I-826J2625D01*
G03X37659Y213478I-2748J146D01*
G02Y215058I613J790D01*
G03X38776Y217222I-1635J2214D01*
G03X38180Y218982I-2752J49D01*
G03X36986Y219851I-2157J-1709D01*
G01X36845Y219903D01*
X36500Y220374D01*
Y273320D01*
X47019Y283839D01*
X75900D01*
X76426Y283313D01*
X91952D01*
X96760Y278505D01*
Y252818D01*
G03Y241670I5602J-5574D01*
G01Y233744D01*
X96146Y233130D01*
X95977Y233108D01*
G03X94849Y230899I191J-1490D01*
G01X94910Y230787D01*
Y221451D01*
X97160Y219201D01*
Y161992D01*
X91323Y156155D01*
X81249D01*
G37*
G36*
G01X51473Y465082D02*
G03X50542Y467033I-1643J414D01*
G02X50258Y467416I211J453D01*
G02X50585Y468307I990J142D01*
G03X50587Y470555I-995J1125D01*
G02X50426Y471866I665J747D01*
G03X49002Y474204I-1241J847D01*
G02X47880Y475196I-122J992D01*
G01Y476083D01*
G02X49178Y477038I1000J0D01*
G03X50798Y479410I447J1434D01*
G01X50689Y479547D01*
Y479897D01*
X50798Y480034D01*
G03X49178Y482406I-1173J938D01*
G02X47880Y483361I-298J955D01*
G01Y486922D01*
G02X49186Y487874I1000J0D01*
G03X50818Y490242I459J1430D01*
G01X50709Y490379D01*
Y490729D01*
X50818Y490866D01*
G03X49773Y493301I-1173J938D01*
G02X48868Y494433I86J996D01*
G03X48613Y495496I-1488J205D01*
G01X48612Y495497D01*
G02X48670Y496136I411J285D01*
G01X49168Y496634D01*
X49490Y496684D01*
X49636Y496608D01*
G03X51230Y496738I694J1332D01*
G02X52430I600J-800D01*
G03X53867Y499343I900J1202D01*
G02X53518Y500984I358J934D01*
G01X56141Y503607D01*
X59174D01*
G02X60174Y502627I0J-1000D01*
G03X60503Y501718I1502J30D01*
G02Y501094I-391J-312D01*
G03X63051Y499551I1173J-938D01*
G02X64171Y500126I915J-404D01*
G03X65923Y502012I309J1470D01*
G02X66884Y503289I961J277D01*
G01X79338D01*
X79788Y502993D01*
X79848Y502881D01*
G03X82552Y502988I1326J706D01*
G01Y502989D01*
G02X83011Y503289I458J-200D01*
G01X84241D01*
G02X85234Y502172I0J-1000D01*
G03X85355Y501384I1492J-174D01*
G03X85757Y500850I1371J614D01*
G02X85733Y499334I-664J-748D01*
G03X85606Y499215I962J-1154D01*
G01X85541Y499146D01*
X85386Y499074D01*
G02X84948Y499083I-210J454D01*
G01X84765Y499177D01*
X84699Y499258D01*
G03X82543Y497181I-1163J-950D01*
G02X82511Y495653I-661J-750D01*
G03X82282Y493547I944J-1168D01*
G02Y492923I-391J-312D01*
G03Y491047I1173J-938D01*
G02Y490423I-391J-312D01*
G03X84393Y488312I1173J-938D01*
G01X84530Y488421D01*
X84880D01*
X85017Y488312D01*
G03X86933Y488345I938J1173D01*
G02X87584I326J-380D01*
G03X89736Y490422I979J1139D01*
G01X89627Y490559D01*
Y490909D01*
X89736Y491046D01*
G03Y492922I-1173J938D01*
G01X89627Y493059D01*
Y493409D01*
X89736Y493546D01*
G03X87585Y495624I-1173J938D01*
G02X86934I-326J380D01*
G03X86730Y495771I-977J-1141D01*
G02X86915Y496694I258J428D01*
G03X87675Y499318I-220J1486D01*
G02X87688Y500843I653J757D01*
G03X88218Y502172I-962J1154D01*
G02X89211Y503289I993J117D01*
G01X107899D01*
G02X108899Y502263I0J-1000D01*
G03X109208Y501308I1502J-42D01*
G01X109255Y501248D01*
X109371Y500930D01*
X109264Y500623D01*
X109221Y500564D01*
G03X109318Y498677I1215J-884D01*
G01X109375Y498613D01*
X109519Y498266D01*
X109384Y497928D01*
X109330Y497865D01*
G03X111342Y495664I1141J-977D01*
G02X112502I580J-815D01*
G03X114511Y497868I871J1224D01*
G01X114457Y497931D01*
X114320Y498270D01*
X114439Y498591D01*
X114486Y498652D01*
G03X114526Y500443I-1185J922D01*
G01X114484Y500502D01*
X114380Y500804D01*
X114493Y501118D01*
X114538Y501178D01*
G03X114771Y501634I-1201J901D01*
G02X116433Y502045I955J-296D01*
G01X123520Y494958D01*
X128292D01*
G02X129292Y493939I0J-1000D01*
G03X131760Y492760I1502J-29D01*
G02X132435Y492730I321J-383D01*
G01X155500Y469665D01*
Y462551D01*
X153190Y460241D01*
G02X151709Y460314I-707J707D01*
G03X149596Y458201I-1162J-951D01*
G02X149669Y456720I-634J-774D01*
G01X143954Y451004D01*
Y445532D01*
X140646Y442224D01*
G02X139339Y442131I-707J707D01*
G03X137264Y439992I-902J-1201D01*
G02Y439368I-391J-312D01*
G03X136954Y438667I1173J-938D01*
G01X136929Y438507D01*
X135460Y437038D01*
Y423125D01*
X135258Y422858D01*
X135097Y422812D01*
G03Y419922I410J-1445D01*
G01X135258Y419876D01*
X135460Y419609D01*
Y407058D01*
X135001Y406569D01*
X134836Y406541D01*
G03X133901Y404139I252J-1481D01*
G02X133938Y402965I-790J-612D01*
G03X134103Y401075I1243J-844D01*
G02X134093Y399672I-718J-696D01*
G01X126930Y392509D01*
X119409D01*
G02X118430Y393714I0J1000D01*
G03X115490I-1470J309D01*
G02X114511Y392509I-979J-205D01*
G01X109980D01*
G02X109001Y393714I0J1000D01*
G03X106030Y393968I-1470J309D01*
G02X105031Y392932I-999J-36D01*
G01X77999D01*
X75190Y395741D01*
G02X75086Y397034I707J708D01*
G03X72989Y399131I-1218J879D01*
G02X71696Y399235I-585J811D01*
G01X59359Y411572D01*
X59304Y411879D01*
X59368Y412021D01*
G03X57380Y414009I-1368J620D01*
G01X57238Y413945D01*
X56931Y414000D01*
X47880Y423051D01*
Y427853D01*
G02X49184Y428806I1000J0D01*
G03X51011Y430851I456J1431D01*
G02X51694Y432233I913J409D01*
G03X50177Y434634I-344J1462D01*
G02X48607Y434646I-780J625D01*
G03X48140Y435043I-1186J-922D01*
G01X48139Y435044D01*
G02X47880Y435482I241J438D01*
G01Y462036D01*
G02X48183Y462496I500J0D01*
G03X49066Y463598I-593J1380D01*
G01X49096Y463755D01*
X49250Y463904D01*
G03X49771Y463803I579J1592D01*
G02X50113Y463650I-18J-500D01*
G01X50172Y463589D01*
X50243Y463366D01*
X50239Y463343D01*
G03X52063Y464335I1431J-458D01*
G02X51591Y464620I261J965D01*
G02X51473Y465082I367J340D01*
G37*
G36*
G01X115700Y78214D02*
G02X115200Y78714I0J500D01*
G01Y102607D01*
X115480Y102897D01*
X115682Y102904D01*
G03X116372Y103100I-54J1501D01*
G03X116721Y105435I-744J1305D01*
G03X114563Y105464I-1093J-1030D01*
G02X113159Y105474I-697J717D01*
G01X99679Y118954D01*
G02X99645Y120332I707J707D01*
G03X99800Y122144I-1114J1008D01*
G03X98741Y122827I-1268J-804D01*
G02X98311Y123322I70J495D01*
G01Y220697D01*
X96060Y222948D01*
Y229117D01*
X100350Y233407D01*
Y238399D01*
G02X101440Y239395I1000J0D01*
G03Y255093I922J7849D01*
G02X100350Y256089I-90J996D01*
G01Y257735D01*
X98711Y259374D01*
Y279600D01*
X94180Y284131D01*
X92550D01*
X92367Y284314D01*
X81228D01*
X81190Y284353D01*
X76961D01*
X75390Y285924D01*
Y290705D01*
X76081Y291396D01*
X84513D01*
X84578Y291332D01*
X96634D01*
G02X96987Y291186I0J-500D01*
G01X107305Y280867D01*
X117210Y247408D01*
Y230876D01*
X111050Y224716D01*
Y195421D01*
G02X109608Y194524I-1000J0D01*
G03Y191864I-698J-1330D01*
G02X111050Y190967I442J-897D01*
G01Y186622D01*
X111045Y186585D01*
G03Y186141I1485J-222D01*
G01X111050Y186104D01*
Y162651D01*
X110867Y162391D01*
X110717Y162338D01*
G03Y159508I503J-1415D01*
G01X110868Y159454D01*
X111050Y159195D01*
Y121745D01*
X127660Y105135D01*
Y104942D01*
X128360Y104242D01*
Y100306D01*
X127984Y99829D01*
X127845Y99781D01*
G03Y96939I485J-1421D01*
G01X127984Y96891D01*
X128360Y96414D01*
Y93075D01*
X128340Y93005D01*
G03Y92155I1440J-425D01*
G01X128360Y92085D01*
Y87724D01*
X128290Y87606D01*
G03Y86068I1290J-769D01*
G01X128360Y85950D01*
Y78914D01*
X127660Y78214D01*
X115700D01*
G37*
G36*
G01X245506Y571570D02*
X239895Y565960D01*
X237171D01*
X236683Y566422D01*
X236655Y566587D01*
G03X233942Y566433I-1348J-229D01*
G01X233931Y566234D01*
X233642Y565960D01*
X233168D01*
G02X232670Y566415I0J500D01*
G03X229770Y566567I-1461J-133D01*
G01X229738Y566406D01*
X229250Y565960D01*
X220753D01*
G02X220302Y566242I-1J500D01*
G03X217598I-1352J-653D01*
G02X217147Y565960I-450J218D01*
G01X213292D01*
G02X212292Y566946I0J1000D01*
G03X209288I-1502J-20D01*
G02X208288Y565960I-1000J14D01*
G01X200160D01*
G02X199180Y567161I0J1000D01*
G03X196238I-1471J303D01*
G02X195258Y565960I-980J-201D01*
G01X171551D01*
X169456Y563865D01*
X169256Y563860D01*
G03X167791Y562395I37J-1502D01*
G01X167786Y562195D01*
X164510Y558919D01*
G02X164182Y558773I-354J353D01*
G03X162759Y557350I77J-1500D01*
G01X162749Y557158D01*
X160030Y554439D01*
Y546415D01*
G02X159093Y545417I-1000J0D01*
G03Y542489I92J-1464D01*
G02X160030Y541491I-63J-998D01*
G01Y540975D01*
X156426Y537371D01*
G02X155923Y537248I-353J354D01*
G01X155778Y537293D01*
X155722Y537327D01*
X155720Y537328D01*
G03X154160Y537323I-776J-1245D01*
G01X154159Y537322D01*
X154103Y537287D01*
X153955Y537240D01*
G02X153451Y537364I-150J477D01*
G01X152420Y538395D01*
Y553115D01*
X152287Y553248D01*
X140020D01*
Y519114D01*
G02X139158Y518124I-1000J0D01*
G03X138158Y515741I207J-1488D01*
G02X138173Y514571I-803J-595D01*
G03X139173Y512223I1229J-864D01*
G02X140020Y511234I-153J-988D01*
G01Y504290D01*
G02X139520Y503790I-500J0D01*
G01X120570D01*
G02X120070Y504290I0J500D01*
G01Y514038D01*
G02X121449Y514963I1000J0D01*
G03Y517743I569J1390D01*
G02X120070Y518668I-379J925D01*
G01Y560917D01*
X140316Y581164D01*
G02X140669Y581310I353J-354D01*
G01X154502D01*
X155126Y581934D01*
G02X155730Y582014I354J-353D01*
G03X157781Y584065I750J1301D01*
G02X157860Y584668I433J250D01*
G01X159594Y586402D01*
G02X160135Y586512I354J-354D01*
G03X162191Y587732I564J1392D01*
G02X163184Y588617I993J-115D01*
G01X164115D01*
G02X165110Y587714I0J-1000D01*
G03X165687Y586672I1495J147D01*
G02X165673Y585078I-612J-792D01*
G03X167488Y585062I897J-1204D01*
G02X167502Y586656I612J792D01*
G03X168100Y587714I-897J1205D01*
G02X169095Y588617I995J-97D01*
G01X175925D01*
G02X176920Y587710I-1J-1000D01*
G03X179160Y586544I1496J139D01*
G02X180325Y586419I496J-868D01*
G03X182831Y587584I1005J1116D01*
G02X183831Y588617I1000J33D01*
G01X195723D01*
X195855Y588521D01*
G03X197625I885J1214D01*
G01X197757Y588617D01*
X218687D01*
X226742Y596672D01*
G02X228177Y596651I707J-707D01*
G03X230300Y598774I1092J1031D01*
G02X230279Y600209I686J728D01*
G01X231597Y601527D01*
X248305D01*
X248638Y601400D01*
G03X250642I1002J1119D01*
G01X250975Y601527D01*
X259733D01*
X259780Y601518D01*
G03X260348I284J1475D01*
G01X260395Y601527D01*
X303741D01*
G02X304735Y600421I0J-1000D01*
G03X307723I1494J-158D01*
G02X308717Y601527I994J106D01*
G01X320832D01*
X320978Y601673D01*
X340742D01*
G02X341548Y600081I0J-1000D01*
G03X343970I1211J-888D01*
G02X344776Y601673I806J592D01*
G01X349852D01*
G02X350696Y600137I0J-1000D01*
G03X352554Y600713I1268J-805D01*
G01X352390Y600783D01*
X352307Y600942D01*
G02X352435Y601561I443J231D01*
G01X352573Y601673D01*
X353557D01*
X353904Y601528D01*
X353968Y601471D01*
X353969Y601470D01*
G03X355977I1004J1118D01*
G01X355978Y601471D01*
X356042Y601528D01*
X356389Y601673D01*
X359280D01*
X359616Y601540D01*
X359679Y601488D01*
G03X361615I968J1148D01*
G01X361678Y601540D01*
X362014Y601673D01*
X388558D01*
G02X389058Y601173I0J-500D01*
G01Y597381D01*
X391476Y594964D01*
X404391D01*
G02X405387Y594048I0J-1000D01*
G03X405829Y593107I1497J129D01*
G02Y592394I-351J-357D01*
G03X407936Y592391I1052J-1072D01*
G02Y593104I351J357D01*
G03X408154Y593374I-1052J1072D01*
G01X408218Y593475D01*
X408375Y593569D01*
G02X408916Y593552I257J-429D01*
G01X409109Y593419D01*
X409167Y593299D01*
Y593298D01*
G03X411460Y592774I1355J649D01*
G01X411596Y592883D01*
X411948D01*
X412084Y592774D01*
G03X414524Y593957I938J1173D01*
G02X415524Y594964I1000J7D01*
G01X416117D01*
X420882Y599728D01*
Y601272D01*
G02X421382Y601772I500J0D01*
G01X422763D01*
X428220Y607229D01*
X429542D01*
G02X430036Y606807I0J-500D01*
G01Y606806D01*
G03X432974Y606661I1484J233D01*
G01Y606662D01*
X433014Y606814D01*
X433498Y607229D01*
X439294D01*
X439396Y607181D01*
G03X440684I644J1356D01*
G01X440786Y607229D01*
X485177D01*
X487982Y604424D01*
Y604400D01*
X488006D01*
X488908Y603498D01*
Y602492D01*
X487548Y601133D01*
Y599267D01*
X488867Y597948D01*
X490733D01*
X491842Y599058D01*
X493348D01*
X500727Y591680D01*
G02X500227Y589994I-707J-707D01*
G03X499142Y587970I311J-1469D01*
G02X498874Y586851I-929J-369D01*
G03X501264Y586280I994J-1126D01*
G02X501532Y587399I929J369D01*
G03X502007Y588214I-994J1125D01*
G02X503693Y588714I979J-207D01*
G01X504380Y588027D01*
Y554626D01*
G02X503880Y554126I-500J0D01*
G01X502409D01*
G02X501461Y555445I0J1000D01*
G03X501183Y556897I-1423J480D01*
G02X501208Y557571I381J323D01*
G03X498993Y557653I-1070J1054D01*
G02X498968Y556979I-381J-323D01*
G03X498615Y555445I1070J-1054D01*
G02X497667Y554126I-948J-319D01*
G01X487172D01*
X485342Y555956D01*
X485340Y556161D01*
G03X483851Y557650I-1502J-13D01*
G01X483646Y557652D01*
X471732Y569566D01*
X464631Y576668D01*
X433458D01*
X433020Y577106D01*
X414587D01*
X412135Y574654D01*
X402212D01*
X399060Y571502D01*
X319258D01*
G02X318271Y572662I0J1000D01*
G03X315447Y572229I-1482J241D01*
G01X315500Y572123D01*
Y572002D01*
G02X315000Y571502I-500J0D01*
G01X314863D01*
X314491Y571673D01*
X314426Y571740D01*
G03X312268I-1079J-1045D01*
G01X312203Y571673D01*
X311831Y571502D01*
X306896D01*
G02X305903Y572614I1J1000D01*
G03X302917I-1493J168D01*
G02X301924Y571502I-994J-112D01*
G01X287982D01*
G02X287002Y572702I0J1000D01*
G03X284058I-1472J300D01*
G02X283078Y571502I-980J-200D01*
G01X269584D01*
X269357Y571629D01*
X269289Y571740D01*
G03X266730I-1280J-787D01*
G01X266662Y571629D01*
X266435Y571502D01*
X261020D01*
X260952Y571570D01*
X245506D01*
G37*
G36*
G01X144837Y309778D02*
X150752D01*
X155976D01*
X157300Y308454D01*
Y296379D01*
X156088Y295167D01*
X150357D01*
X144262D01*
X143574Y295855D01*
Y299713D01*
Y308515D01*
X144837Y309778D01*
G37*
G36*
G01X200412Y402059D02*
G03X202769Y403267I855J1235D01*
G02X203269Y403758I500J-9D01*
G01X220817D01*
G02X221723Y402336I0J-1000D01*
G03X224447I1362J-634D01*
G02X225353Y403758I906J422D01*
G01X226634D01*
X231160Y399232D01*
Y396225D01*
X231156Y396195D01*
G03Y395827I1491J-184D01*
G01X231160Y395797D01*
Y393179D01*
X230960Y392912D01*
X230801Y392865D01*
G03X230562Y390075I422J-1441D01*
G02X230799Y389423I-220J-449D01*
G03X231038Y387830I1373J-608D01*
G01X231160Y387689D01*
Y382299D01*
X228545Y379684D01*
X212995D01*
X199085Y365774D01*
X173030D01*
X164850Y357594D01*
Y350188D01*
G02X164367Y349688I-500J0D01*
G03Y346686I51J-1501D01*
G02X164850Y346186I-17J-500D01*
G01Y335973D01*
X164809Y335879D01*
G03Y334691I1380J-594D01*
G01X164850Y334597D01*
Y291982D01*
G02X164350Y291482I-500J0D01*
G01X164000D01*
G02X163168Y293036I0J1000D01*
G03X160668I-1250J833D01*
G02X159836Y291482I-832J-554D01*
G01X159557D01*
G02X159187Y291646I0J500D01*
G03X156965I-1111J-1011D01*
G02X156595Y291482I-370J336D01*
G01X152172D01*
G02X151192Y292684I-1J1000D01*
G03X151219Y293094I-1471J303D01*
G02X152217Y294166I998J72D01*
G01X156503D01*
X158302Y295964D01*
Y308869D01*
X156391Y310780D01*
X148182D01*
G02X147198Y311602I0J1000D01*
G03X144264Y310967I-1478J-265D01*
G02X144133Y310490I-485J-123D01*
G01X142572Y308930D01*
Y295440D01*
X143847Y294166D01*
X147225D01*
G02X148223Y293094I0J-1000D01*
G03X148250Y292684I1498J-107D01*
G02X147270Y291482I-979J-202D01*
G01X142055D01*
G02X141213Y293023I-1J1000D01*
G03X138466Y293603I-1263J812D01*
G02X137657Y292465I-988J-154D01*
G03X137052Y292209I269J-1478D01*
G02X136408Y292263I-290J407D01*
G01X135760Y292911D01*
Y299319D01*
G02X136892Y300310I1000J0D01*
G03X137694Y303175I200J1489D01*
G02X137309Y304710I401J916D01*
G03X136228Y307139I-1179J930D01*
G02X135760Y307638I32J499D01*
G01Y312782D01*
X135964Y313050D01*
X136128Y313095D01*
G03Y315991I-398J1448D01*
G02X135760Y316474I132J482D01*
G01Y317708D01*
G02X135887Y318041I500J0D01*
G03Y320045I-1119J1002D01*
G02X135760Y320378I373J333D01*
G01Y321962D01*
X135888Y322189D01*
X136001Y322258D01*
G03Y324828I-777J1285D01*
G01X135888Y324897D01*
X135760Y325124D01*
Y329704D01*
G02X136658Y330699I1000J0D01*
G03Y333687I-152J1494D01*
G02X135760Y334682I102J995D01*
G01Y340222D01*
X135886Y340348D01*
X143220Y356075D01*
Y364466D01*
X154602Y375848D01*
X158286D01*
X158557Y375634D01*
X158598Y375465D01*
G03X161518I1460J353D01*
G02X162004Y375848I486J-117D01*
G01X166335D01*
X166593Y375668D01*
X166647Y375520D01*
G03X169469I1411J515D01*
G02X169938Y375848I469J-172D01*
G01X174471D01*
G02X174867Y375653I0J-500D01*
G03X177249I1191J915D01*
G02X177645Y375848I396J-305D01*
G01X182406D01*
G02X182819Y375630I0J-500D01*
G03X185297I1239J849D01*
G02X185710Y375848I413J-282D01*
G01X186479D01*
X192504Y381873D01*
G02X193041Y381985I354J-353D01*
G03X194988Y383932I549J1398D01*
G02X195100Y384469I465J183D01*
G01X195210Y384579D01*
Y388918D01*
G02X195341Y389255I500J0D01*
G03Y391279I-1110J1012D01*
G02X195210Y391616I369J337D01*
G01Y394975D01*
G02X195365Y395337I500J0D01*
G03X195585Y397250I-1035J1088D01*
G02X195650Y397878I418J274D01*
G01X199902Y402130D01*
X200263Y402162D01*
X200412Y402059D01*
G37*
G36*
G01X144800Y486661D02*
X141816Y489645D01*
Y549938D01*
X144124Y552246D01*
X150918D01*
G02X151418Y551746I0J-500D01*
G01Y537980D01*
X153480Y535919D01*
X153511Y535775D01*
G03X156383Y535794I1434J309D01*
G01X156413Y535942D01*
X157250Y536779D01*
G02X157957I354J-354D01*
G01X157980Y536757D01*
X157999Y536732D01*
G03X158367Y536394I1186J922D01*
G02X158347Y535708I-949J-316D01*
G03X158056Y533568I839J-1204D01*
G02X158075Y532316I-770J-638D01*
G03X157876Y530694I1110J-959D01*
G03X158028Y530454I1309J661D01*
G02X158003Y529207I-794J-608D01*
G03X160114Y527088I1156J-960D01*
G02X161392Y527082I635J-772D01*
G03X163802Y528176I943J1124D01*
G03X161410Y529344I-1467J30D01*
G02X160091Y529432I-610J793D01*
G01X160012Y529593D01*
G02Y530031I449J219D01*
G01X160093Y530199D01*
X160166Y530265D01*
G03X160315Y532292I-981J1091D01*
G02X160300Y533550I770J638D01*
G03X160024Y535708I-1114J954D01*
G02X160003Y536394I928J372D01*
G03X160579Y537096I-819J1259D01*
G01X160630Y537222D01*
X161008Y537515D01*
G02X161668Y537473I306J-395D01*
G01X162902Y536238D01*
G02X163049Y535885I-353J-354D01*
G01Y533313D01*
X167891Y528471D01*
G02X167777Y526959I-707J-707D01*
G03X167371Y526531I840J-1203D01*
G03X167152Y525837I1246J-775D01*
G02X166427Y524931I-998J56D01*
G03X165926Y522292I410J-1445D01*
G03X168338Y523438I911J1194D01*
G02X169032Y524349I999J-41D01*
G03X169389Y524509I-416J1407D01*
G03X170016Y525313I-771J1248D01*
G01X170053Y525429D01*
X170139Y525515D01*
G02X170847I354J-353D01*
G01X170909Y525453D01*
X173395D01*
X180119Y518729D01*
Y516576D01*
X180029Y516447D01*
G03Y514767I1203J-840D01*
G01X180119Y514638D01*
Y513864D01*
G02X179996Y513535I-500J-1D01*
G03X179957Y513488I1243J-1071D01*
G02X179197Y513466I-389J314D01*
G03X176660Y512931I-1112J-1010D01*
G03X178706Y511088I1425J-475D01*
G02X180119Y510178I413J-911D01*
G01Y509340D01*
X183409Y506050D01*
X200195D01*
X209402Y515257D01*
G02X210469Y515483I707J-707D01*
G03X212790Y515529I1140J1070D01*
G02X213489Y515565I398J-917D01*
G03X215734Y515530I1137J927D01*
G02X216377Y515494I269J-963D01*
G03X216918Y515019I1233J858D01*
G03X219028Y515860I691J1334D01*
G03X216460Y517321I-1419J494D01*
G02X215818Y517347I-283J960D01*
G03X215524Y517652I-1192J-855D01*
G03X213599Y517540I-898J-1160D01*
G01X213534Y517476D01*
X213397Y517415D01*
G02X212811Y517552I-202J458D01*
G03X212679Y517692I-1201J-1000D01*
G02X212905Y518760I933J361D01*
G01X220517Y526372D01*
X228225D01*
G02X229225Y525405I0J-1000D01*
G03X229639Y523434I1251J-766D01*
G02Y522694I-930J-370D01*
G03Y520284I837J-1205D01*
G02Y519544I-930J-370D01*
G03X229023Y518136I837J-1205D01*
G03X229637Y517135I1453J202D01*
G02X229638Y516394I-928J-372D01*
G01X229571Y516226D01*
X219199Y505854D01*
Y496186D01*
X213372Y490359D01*
X213172Y490355D01*
G03X211707Y488890I37J-1502D01*
G01X211703Y488690D01*
X209674Y486661D01*
X202928D01*
G02X201941Y487498I0J1000D01*
G03X198977I-1482J-245D01*
G02X197990Y486661I-987J163D01*
G01X188249D01*
G02X187249Y487662I0J1000D01*
G03X184245I-1502J2D01*
G02X183245Y486661I-1000J-1D01*
G01X172230D01*
G02X171230Y487662I0J1000D01*
G03X168226I-1502J2D01*
G02X167226Y486661I-1000J-1D01*
G01X144800D01*
G37*
G36*
G01X158210Y660136D02*
Y646724D01*
X184730D01*
Y660136D01*
X158210D01*
G37*
G36*
G01X218989Y304406D02*
G02X219343Y304259I0J-500D01*
G01X219829Y303772D01*
Y302622D01*
X219264Y302057D01*
X217953D01*
X217498Y301602D01*
Y300940D01*
X217386Y300828D01*
Y298120D01*
X219299Y296207D01*
Y283672D01*
X218266Y282639D01*
X204792D01*
Y280701D01*
X204143Y280052D01*
X197894D01*
X197150Y280796D01*
Y292650D01*
X197316Y292901D01*
X197455Y292960D01*
G03Y295724I-588J1382D01*
G01X197316Y295783D01*
X197150Y296034D01*
Y301056D01*
X196347Y301859D01*
X196271Y302047D01*
X196273Y302149D01*
G03X194746Y303678I-1502J27D01*
G01X194740D01*
G02X194382Y303824I-5J500D01*
G01X191180Y307026D01*
Y310561D01*
X192740Y312121D01*
Y314571D01*
G02X193827Y315568I1000J1D01*
G03X194838Y315847I131J1496D01*
G01X194897Y315890D01*
X195203Y315997D01*
X195516Y315885D01*
X195576Y315840D01*
G03X195595Y318259I900J1203D01*
G01X195536Y318216D01*
X195230Y318109D01*
X194917Y318221D01*
X194857Y318266D01*
G03X193827Y318560I-900J-1202D01*
G02X192740Y319557I-87J996D01*
G01Y323027D01*
G02X193569Y324012I1000J0D01*
G03X194495Y326419I-256J1480D01*
G02X194574Y327743I787J617D01*
G01X197150Y330319D01*
X200993D01*
X201754Y329558D01*
Y326384D01*
G02X200681Y325418I-1000J32D01*
G03X199276Y323161I-109J-1498D01*
G02X199186Y322543I-432J-253D01*
G03X200457Y319964I1025J-1097D01*
G02X201620Y318978I163J-987D01*
G01Y316032D01*
X201604Y315970D01*
G03Y315216I1454J-377D01*
G01X201620Y315154D01*
Y313504D01*
X201704Y313420D01*
X201771Y313151D01*
X201730Y313018D01*
G03X204114Y311412I1436J-441D01*
G02X205366Y311421I632J-775D01*
G03X207245Y311431I933J1177D01*
G02X208503I629J-777D01*
G03X210931Y312842I946J1167D01*
G02X211918Y314005I987J163D01*
G01X215090D01*
X216288Y315203D01*
X219759D01*
X220907Y314055D01*
Y313586D01*
X220817Y313457D01*
G03X220548Y312537I1232J-860D01*
G01Y312522D01*
G02X220402Y312157I-500J-12D01*
G01X219540Y311295D01*
X218104D01*
X217272Y310463D01*
Y304879D01*
X217745Y304406D01*
X218989D01*
G37*
G36*
G01X215224Y459685D02*
X215210Y459699D01*
X206510D01*
G02X206010Y460199I0J500D01*
G01Y462001D01*
X206029Y462068D01*
G03Y462888I-1445J410D01*
G01X206010Y462955D01*
Y471599D01*
G02X206510Y472099I500J0D01*
G01X220810D01*
G02X221310Y471599I0J-500D01*
G01Y460185D01*
G02X220810Y459685I-500J0D01*
G01X215224D01*
G37*
G36*
G01X338729Y552225D02*
G03X338832Y552156I887J1213D01*
G02X339071Y551730I-261J-426D01*
G01Y542760D01*
X339010Y542648D01*
G03Y541214I1320J-717D01*
G01X339071Y541102D01*
Y540256D01*
X332396Y533581D01*
G02X330753Y533934I-708J707D01*
G03X328817Y531998I-1405J-531D01*
G02X329170Y530355I-354J-935D01*
G01X301944Y503129D01*
X291808D01*
X291786Y503151D01*
X291738D01*
X291521Y503266D01*
X291450Y503368D01*
G03X289196I-1127J-773D01*
G01X289125Y503266D01*
X288908Y503151D01*
X285439D01*
X285222Y503266D01*
X285151Y503368D01*
G03X282775Y503151I-1127J-773D01*
G01X282711D01*
X282368Y503494D01*
X281651D01*
X281004Y504141D01*
X280153D01*
X279831Y504261D01*
X279767Y504312D01*
G03X278512Y504755I-1256J-1558D01*
G01X276741D01*
X275924Y503938D01*
G02X275319Y503859I-354J354D01*
G03X275007Y501188I-738J-1268D01*
G01X275078Y501209D01*
X275154D01*
G02X275654Y500709I0J-500D01*
G01Y493869D01*
X269498Y487713D01*
Y474963D01*
X271478Y472983D01*
X273758D01*
X274638Y472103D01*
Y462453D01*
X272698Y460513D01*
X266293D01*
G02X265300Y461401I1J1000D01*
G03X262314I-1493J-167D01*
G02X261321Y460513I-994J112D01*
G01X260070D01*
G02X259070Y461513I0J1000D01*
G03X256069Y461609I-1502J0D01*
G01X256057Y461421D01*
X255924Y461287D01*
G02X255217I-353J354D01*
G01X254743Y461761D01*
X254723Y461786D01*
X254721Y461788D01*
G03X254460Y462049I-1184J-923D01*
G01X254458Y462051D01*
X254433Y462071D01*
X254411Y462093D01*
X254353Y462127D01*
X254345Y462132D01*
X254334Y462138D01*
G03X253689Y462359I-797J-1273D01*
G03X252892Y462221I-152J-1494D01*
G02X252453Y462226I-214J452D01*
G03X250999Y462166I-673J-1343D01*
G01X250879Y462093D01*
X233255D01*
X232963Y462385D01*
Y462593D01*
G03X229959I-1502J-2D01*
G01Y462385D01*
X229667Y462093D01*
X226854D01*
X226773Y462121D01*
G03X225779I-497J-1417D01*
G01X225698Y462093D01*
X223332D01*
X222312Y463113D01*
Y473101D01*
X222078Y473335D01*
Y473869D01*
X219974D01*
G02X219491Y474240I0J500D01*
G03X216589I-1451J-387D01*
G02X216106Y473869I-483J129D01*
G01X213198D01*
X210648Y476419D01*
Y485846D01*
X212244Y487442D01*
X212534Y487503D01*
X212672Y487450D01*
G03X212914Y487380I537J1403D01*
G03X213199Y487351I294J1473D01*
G03X213235I18J1502D01*
G03X213540Y487388I-27J1502D01*
G03X214080Y487629I-330J1465D01*
G03X214099Y487643I-881J1216D01*
G03X214127Y487664I-887J1212D01*
G02X215291I582J-813D01*
G03X216832Y487486I918J1189D01*
G03X217565Y488206I-623J1367D01*
G03X217527Y489574I-1356J647D01*
G02X218404Y491054I877J480D01*
G01X221908D01*
X223489Y489473D01*
X240854D01*
X248364Y496983D01*
Y500124D01*
G02X249368Y501124I1000J0D01*
G03X250311Y501462I6J1467D01*
G02X251587I638J-770D01*
G03X252075Y501194I937J1129D01*
G03X252769Y501145I447J1397D01*
G03X253487Y501484I-244J1447D01*
G02X254710I612J-792D01*
G03X257118Y502339I963J1107D01*
G03X257029Y503151I-1445J252D01*
G03X256802Y503528I-1356J-560D01*
G02Y504804I770J638D01*
G03Y506678I-1129J937D01*
G02Y507954I770J638D01*
G03X257029Y508331I-1129J937D01*
G03X257118Y509143I-1356J560D01*
G03X254710Y509998I-1445J-252D01*
G02X253487I-611J792D01*
G03X252769Y510337I-962J-1108D01*
G03X252075Y510288I-247J-1446D01*
G03X251587Y510020I449J-1397D01*
G02X250247Y510078I-638J770D01*
G01X250165Y510241D01*
G02Y510689I447J224D01*
G01X250250Y510858D01*
X250327Y510924D01*
G03X250720Y511456I-953J1115D01*
G03X250771Y511592I-1346J582D01*
G03X250840Y512100I-1397J448D01*
G03X250088Y513322I-1466J-60D01*
G03X248437Y513169I-714J-1282D01*
G02X247161I-638J770D01*
G03X247145Y513182I-933J-1132D01*
G03X247080Y513232I-927J-1137D01*
G03X246650Y513444I-855J-1192D01*
G03X246623Y513452I-430J-1402D01*
G03X246088Y513501I-399J-1412D01*
G02X245028Y514499I-60J998D01*
G01Y514715D01*
G02X245861Y515701I1000J0D01*
G03X247047Y517617I-252J1481D01*
G03X244808Y518453I-1438J-435D01*
G03X244552Y518250I800J-1272D01*
G03X244535Y518232I1083J-1040D01*
G02X243131Y518243I-696J718D01*
G01X241133Y520241D01*
X241092Y520583D01*
X241181Y520731D01*
G03X241054Y522426I-1256J758D01*
G02Y523702I770J638D01*
G03X241322Y524190I-1129J937D01*
G03X241377Y524429I-1397J447D01*
G03X241392Y524672I-1452J212D01*
G03X241065Y525563I-1467J-33D01*
G03X241032Y525602I-1136J-928D01*
G02Y526825I792J612D01*
G03X241262Y527184I-1107J962D01*
G03X241174Y528558I-1337J604D01*
G03X240291Y529209I-1249J-770D01*
G03X239828Y529252I-365J-1421D01*
G02X238806Y530252I-22J1000D01*
G01Y531623D01*
G02X239828Y532623I1000J0D01*
G03X241244Y533445I97J1464D01*
G03X241032Y535050I-1319J642D01*
G02Y536273I792J611D01*
G03X238751Y538115I-1106J963D01*
G02X237950I-401J300D01*
G03X237924Y538149I-1178J-874D01*
G03X237910Y538167I-1165J-891D01*
G03X237905Y538173I-1129J-935D01*
G02Y539449I770J638D01*
G03Y541323I-1129J937D01*
G02Y542599I770J638D01*
G03X238173Y543087I-1129J937D01*
G03X238222Y543781I-1397J447D01*
G03X237883Y544499I-1447J-244D01*
G02X237885Y545725I792J612D01*
G03X238203Y546345I-1109J960D01*
G03X238173Y547134I-1427J341D01*
G03X237905Y547622I-1397J-449D01*
G02Y548898I770J638D01*
G03X238173Y549386I-1129J937D01*
G03X238203Y550175I-1397J448D01*
G03X237885Y550795I-1427J-340D01*
G02Y552024I790J615D01*
G01Y553946D01*
G02X237905Y555197I790J613D01*
G03X238234Y556291I-1129J936D01*
G02X238378Y556698I497J53D01*
G01X239181Y557501D01*
X242159D01*
X242257Y557457D01*
G03X242482Y557372I819J1827D01*
G03X242561Y557350I576J1916D01*
G03X242932Y557288I514J1934D01*
G03X242956Y557286I178J1993D01*
G03X242996Y557284I120J1998D01*
G03X243560Y557342I79J2000D01*
G02X244763Y556270I207J-978D01*
G03X246283Y554668I1461J-136D01*
G03X246511Y554695I-58J1466D01*
G03X247174Y555016I-287J1439D01*
G02X248468Y554952I609J-793D01*
G01X248553Y554783D01*
G02Y554334I-447J-225D01*
G01X248468Y554166D01*
X248391Y554100D01*
G03X247947Y553432I953J-1115D01*
G03X247880Y552890I1397J-448D01*
G03X247883Y552847I1465J81D01*
G03X248247Y552010I1461J138D01*
G02X248236Y550761I-787J-618D01*
G03X247952Y549474I1138J-926D01*
G03X247997Y549329I1421J362D01*
G03X248764Y548501I1377J506D01*
G03X250471Y550809I610J1334D01*
G02X250482Y552058I787J618D01*
G03X250473Y553921I-1138J926D01*
G02Y555197I770J638D01*
G03X250675Y555516I-1128J938D01*
G03X249631Y557573I-1331J618D01*
G03X248651Y557427I-287J-1439D01*
G03X248394Y557252I692J-1293D01*
G02X247100Y557316I-609J793D01*
G01X247015Y557485D01*
G02Y557934I447J225D01*
G01X247100Y558102D01*
X247177Y558168D01*
G03X247353Y560221I-953J1116D01*
G02Y561497I770J638D01*
G03X247588Y562975I-1129J937D01*
G01X247533Y563114D01*
X247594Y563407D01*
X250877Y566690D01*
X251087Y566901D01*
X251910Y567724D01*
Y567732D01*
X253125Y568947D01*
X259267D01*
G02X259744Y568599I1J-500D01*
G03X262606I1431J455D01*
G02X263083Y568947I476J-152D01*
G01X315053D01*
G02X315462Y568736I1J-500D01*
G03X317914I1226J867D01*
G01X317985Y568835D01*
X318201Y568947D01*
X325626D01*
G02X326610Y567770I0J-1000D01*
G03X328046Y566002I1478J-267D01*
G02X328965Y565322I-29J-1000D01*
G03X331888Y565726I1423J481D01*
G01X331898Y565926D01*
X332187Y566201D01*
X332388D01*
G03X333497Y566690I0J1502D01*
G02X334942Y566722I738J-675D01*
G01X337937Y563727D01*
X337975Y563624D01*
G03X338242Y563169I1409J521D01*
G02Y562519I-380J-325D01*
G03X337917Y561223I1142J-975D01*
G03X337918Y561217I1482J244D01*
G03X338052Y560850I1466J327D01*
G02X337594Y560119I-444J-231D01*
G03X336377Y557680I-44J-1501D01*
G02Y557056I-391J-312D01*
G03Y555180I1173J-938D01*
G02Y554556I-391J-312D01*
G03X338213Y552270I1173J-938D01*
G02X338729Y552225I221J-449D01*
G37*
G36*
G01X258491Y297482D02*
G03X257910Y294557I-112J-1498D01*
G02X258254Y294082I-156J-475D01*
G01Y286473D01*
X255466Y283685D01*
Y282131D01*
X253472Y280137D01*
X241339D01*
X240995Y280481D01*
X227587D01*
G02X226699Y281020I-1J1000D01*
G03X226580Y281688I-1500J77D01*
G03X226150Y282260I-1381J-590D01*
G03X224338Y282329I-952J-1162D01*
G01X224209Y282239D01*
X221319D01*
X220301Y283257D01*
Y286541D01*
X220647Y286887D01*
Y288180D01*
G02X221466Y289164I1000J0D01*
G03Y291932I583J1384D01*
G02X220647Y292916I181J984D01*
G01Y300780D01*
G02X221466Y301764I1000J0D01*
G03X223266Y302268I583J1384D01*
G02X223982I358J-934D01*
G03X224126Y302097I1218J879D01*
G03X224272Y301966I1074J1050D01*
G02Y301180I-309J-393D01*
G03X225213Y298496I927J-1182D01*
G03X226079Y301215I-14J1502D01*
G02Y301931I934J358D01*
G03X223982Y304028I-880J1217D01*
G02X223266I-358J934D01*
G03X221238Y304412I-1217J-880D01*
G01X221089Y304317D01*
X220739Y304355D01*
X220097Y304997D01*
X220022D01*
X219612Y305408D01*
X218751D01*
G02X218274Y305885I22J500D01*
G01Y307304D01*
X218906Y307936D01*
X219078Y307957D01*
G03X220116Y308568I-179J1491D01*
G02X220832I358J-934D01*
G03X223266I1217J880D01*
G02X223982I358J-934D01*
G03Y310328I1217J880D01*
G02X223266I-358J934D01*
G03X223122Y310499I-1218J-879D01*
G03X222976Y310630I-1074J-1050D01*
G02Y311416I309J393D01*
G03X223526Y312872I-927J1182D01*
G02X224448Y313487I923J-385D01*
G01X236377D01*
X240423Y317533D01*
G02X240897Y317665I354J-353D01*
G03X241165Y317624I360J1458D01*
G03X242743Y318900I93J1499D01*
G02X243238Y319326I495J-74D01*
G01X253204D01*
Y319297D01*
X253738Y318763D01*
G02X253293Y317112I-723J-691D01*
G03X252732Y316809I417J-1443D01*
G02X251409Y316826I-652J758D01*
G03X249470Y316891I-1008J-1113D01*
G02X248223Y316897I-620J785D01*
G03X248212Y314549I-942J-1170D01*
G02X249459Y314543I620J-785D01*
G03X251379Y314573I942J1170D01*
G02X252702Y314556I652J-758D01*
G03X255153Y315252I1008J1113D01*
G02X256804Y315697I960J-278D01*
G01X258076Y314425D01*
G02X257847Y312865I-723J-691D01*
G03X257091Y311655I743J-1305D01*
G02X256711Y311201I-499J32D01*
G03X255568Y309830I356J-1459D01*
G03X257627Y308246I1489J-194D01*
G02X259007Y307321I380J-925D01*
G01Y305202D01*
X258917Y305005D01*
X258835Y304934D01*
G03X258787Y304890I991J-1129D01*
G02X258187Y304823I-344J363D01*
G03X257772Y302073I-769J-1290D01*
G02X259007Y301101I235J-972D01*
G01Y298357D01*
G02X258491Y297482I-1000J0D01*
G37*
G36*
G01X245103Y511094D02*
G03X245862Y510618I1122J945D01*
G02X246238Y510134I-124J-484D01*
G01Y504325D01*
X246029Y504056D01*
X245862Y504013D01*
G03X245288Y503720I364J-1421D01*
G02X244011I-638J770D01*
G03Y501462I-936J-1129D01*
G02X245288I638J-770D01*
G03X245862Y501169I938J1128D01*
G02X246238Y500685I-124J-484D01*
G01Y496463D01*
X240250Y490475D01*
X223904D01*
X222323Y492055D01*
X222316D01*
X220209Y494162D01*
Y497523D01*
X224499Y501813D01*
X225923D01*
G02X226287Y501655I-1J-500D01*
G03X228281I997J936D01*
G02X228645Y501813I365J-342D01*
G01X229115D01*
G02X229479Y501655I-1J-500D01*
G03X231473I997J936D01*
G02X231837Y501813I365J-342D01*
G01X232265D01*
G02X232629Y501655I-1J-500D01*
G03X234895Y503100I997J935D01*
G01X234838Y503241D01*
X234898Y503533D01*
X235468Y504103D01*
Y506443D01*
G02X236593Y507435I1000J0D01*
G03Y510347I183J1456D01*
G02X235468Y511339I-125J992D01*
G01Y513172D01*
X236058Y513762D01*
X236436D01*
X236485Y513752D01*
G03X237852Y514193I291J1438D01*
G02X238219Y514353I367J-340D01*
G01X243718D01*
X244092Y513979D01*
X244129Y513867D01*
G03X244687Y513014I1899J633D01*
G02X244828Y512490I-335J-371D01*
G03X245103Y511094I1396J-450D01*
G37*
G36*
G01X234877Y525405D02*
G02X235877Y526372I1000J-33D01*
G01X236388D01*
X236444Y526359D01*
G03X237108I332J1429D01*
G01X237164Y526372D01*
X237742D01*
X238502Y525611D01*
Y525002D01*
X238491Y524949D01*
G03Y524329I1434J-310D01*
G01X238502Y524276D01*
Y523295D01*
G02X237588Y522711I-909J416D01*
G03X235572Y522327I-812J-1222D01*
G02X234830I-371J929D01*
G03X234505Y522664I-1205J-837D01*
G02Y523464I299J400D01*
G03X234877Y525405I-879J1175D01*
G37*
G36*
G01X285082Y501730D02*
G03X285240Y501970I-1056J867D01*
G02X285684Y502241I444J-229D01*
G01X288804D01*
X289043Y502095D01*
X289107Y501970D01*
G03X291508Y501913I1216J625D01*
G01X291541Y501970D01*
X291734Y502164D01*
X292147D01*
X292184Y502127D01*
X299933D01*
X301657Y500403D01*
Y495371D01*
X301007Y494721D01*
X294624D01*
X294184Y494281D01*
X279580D01*
X276656Y497205D01*
Y503253D01*
X277156Y503753D01*
X278512D01*
G02X278677Y503739I-2J-1000D01*
G01X280838D01*
X282336Y502241D01*
X282505D01*
X282744Y502095D01*
X282808Y501970D01*
G03X282966Y501730I1214J627D01*
G02X282934Y500427I-774J-633D01*
G03X285114I1090J-982D01*
G02X285082Y501730I742J670D01*
G37*
G36*
G01X328850Y342166D02*
X336310D01*
X336690Y341786D01*
Y325056D01*
X336420Y324786D01*
X328680D01*
X328260Y325206D01*
Y341576D01*
X328850Y342166D01*
G37*
G36*
G01X362820Y41214D02*
X362520Y40914D01*
Y31469D01*
X361360Y30309D01*
X349793D01*
X344750Y35352D01*
Y41250D01*
X347849Y44349D01*
X361551D01*
X362820Y43080D01*
Y41214D01*
G37*
G36*
G01X377791Y510377D02*
G03X379756Y508412I1386J-579D01*
G02X380302Y508304I192J-462D01*
G01X385412Y503194D01*
G02Y502487I-354J-353D01*
G01X380345Y497419D01*
G03X383175Y494589I1415J-1415D01*
G01X385809Y497222D01*
G02X387502Y496685I707J-707D01*
G03X390355Y496329I1480J254D01*
G02X391976Y496630I914J-406D01*
G01X393650Y494956D01*
Y474890D01*
X390380Y471620D01*
X379670D01*
G02X378716Y472921I0J1000D01*
G03X375852I-1432J453D01*
G02X374898Y471620I-954J-301D01*
G01X371260D01*
G02X370272Y472771I0J1000D01*
G03X367302I-1485J227D01*
G02X366314Y471620I-988J-151D01*
G01X352560D01*
X344436Y479744D01*
Y487890D01*
X343650Y488677D01*
Y496101D01*
G02X343967Y496567I500J1D01*
G01X343968D01*
G03Y499365I-548J1399D01*
G01X343967D01*
G02X343650Y499831I183J465D01*
G01Y508379D01*
X347346Y512076D01*
G02X347699Y512222I353J-354D01*
G01X348270D01*
X348576Y512528D01*
G02X349284I354J-353D01*
G01X349396Y512415D01*
X349423Y512261D01*
G03X351792Y513730I1479J259D01*
G02X351707Y515271I593J806D01*
G03X352085Y515819I-1017J1106D01*
G01X352142Y515962D01*
X352396Y516134D01*
X372472D01*
X377683Y510923D01*
G02X377791Y510377I-354J-354D01*
G37*
G36*
G01X391891Y595965D02*
X390060Y597796D01*
Y609501D01*
G02X391215Y610489I1000J0D01*
G03Y613457I232J1484D01*
G02X390060Y614445I-155J988D01*
G01Y618802D01*
X393181Y621923D01*
X403313D01*
X403822Y621414D01*
G02X403430Y619758I-707J-707D01*
G03X405403Y618427I474J-1425D01*
G02X406401Y619489I998J62D01*
G01X407588D01*
G02X408586Y618425I0J-1000D01*
G03X411584I1499J-96D01*
G02X412582Y619489I998J64D01*
G01X416508D01*
X419880Y616117D01*
Y600143D01*
X415702Y595965D01*
X403905D01*
G02X402913Y597087I0J1000D01*
G03X402595Y598208I-1491J183D01*
G01X402486Y598345D01*
Y598695D01*
X402595Y598832D01*
G03X400709Y601092I-1173J938D01*
G02X400060Y601249I-237J440D01*
G03X399535Y599077I-1238J-850D01*
G02X399889Y599123I237J-440D01*
G01X400076Y599078D01*
X400185Y598919D01*
G03X400249Y598832I1241J846D01*
G02Y598208I-391J-312D01*
G03X399931Y597087I1173J-938D01*
G02X398939Y595965I-992J-122D01*
G01X391891D01*
G37*
G36*
G01X409437Y484881D02*
Y486821D01*
X410025Y487409D01*
X415920D01*
X416672Y488161D01*
Y501248D01*
X423671Y508247D01*
Y516637D01*
X425020Y517986D01*
X427062D01*
X427882Y517166D01*
Y505917D01*
X420863Y498898D01*
Y485250D01*
X419771Y484158D01*
X413060D01*
X412952Y484214D01*
G03X411568I-692J-1333D01*
G01X411460Y484158D01*
X410118D01*
X409982Y484265D01*
G03X409716Y484432I-927J-1182D01*
G02X409437Y484881I221J449D01*
G37*
G36*
G01X452361Y555230D02*
G03X454015Y553576I1493J-161D01*
G02X454422Y553432I53J-497D01*
G01X455794Y552060D01*
Y551851D01*
G02X455492Y551392I-500J0D01*
G01X455223Y551277D01*
G02X454749Y551320I-197J459D01*
G03X454443Y548662I-832J-1251D01*
G02X455794Y547726I351J-936D01*
G01Y547297D01*
G02X454357Y546398I-1000J0D01*
G03Y543696I-657J-1351D01*
G02X455794Y542797I437J-899D01*
G01Y530939D01*
G02X455651Y530589I-500J0D01*
G03Y528483I1071J-1053D01*
G02X455794Y528133I-357J-350D01*
G01Y524385D01*
X453365Y521956D01*
G02X451824Y522111I-707J707D01*
G03X449760Y520047I-1284J-780D01*
G02X449915Y518506I-552J-834D01*
G01X446046Y514637D01*
Y508276D01*
X442246Y504476D01*
X439024D01*
X437041Y506459D01*
Y507683D01*
X437192Y508038D01*
X437252Y508102D01*
G03Y510152I-1098J1025D01*
G01X437192Y510216D01*
X437041Y510571D01*
Y538630D01*
X437156Y538769D01*
G03X437140Y540702I-1158J957D01*
G01X437020Y540842D01*
Y544838D01*
X434690Y547168D01*
X430541D01*
G02X429541Y548148I0J1000D01*
G03X426554Y548347I-1502J-28D01*
G02X425767Y547519I-988J152D01*
G03X425186Y547263I301J-1471D01*
G01X425054Y547168D01*
X423919D01*
G02X422937Y547982I1J1000D01*
G03X419985I-1476J-279D01*
G02X419003Y547168I-983J186D01*
G01X418313D01*
X418023Y547449D01*
X418016Y547652D01*
G03X415014I-1501J-50D01*
G02X414514Y547168I-500J16D01*
G01X407030D01*
G02X406530Y547668I0J500D01*
G01Y551393D01*
X406540Y551442D01*
G03X406552Y551506I-1961J401D01*
G01X406578Y551663D01*
X407430Y552515D01*
Y560772D01*
X408018Y561360D01*
X446494D01*
X452217Y555637D01*
G02X452361Y555230I-353J-354D01*
G37*
G36*
G01X482515Y655652D02*
G03X479935Y655558I-1262J-815D01*
G02X479496Y655298I-439J240D01*
G01X470542D01*
X470052Y655788D01*
X470033Y655963D01*
G03X467796Y657104I-1493J-164D01*
G03X466298Y655901I-26J-1502D01*
G01X466265Y655740D01*
X465778Y655298D01*
X463936D01*
X463737Y655390D01*
X463665Y655476D01*
G03X462256Y655986I-1148J-969D01*
G03X460849Y655475I-259J-1479D01*
G02X460466Y655298I-382J323D01*
G01X448979D01*
G02X448108Y656789I0J1000D01*
G03X447275Y658951I-1309J737D01*
G02X446664Y660272I317J948D01*
G03X444794Y659407I-1394J560D01*
G02X445405Y658086I-317J-948D01*
G03X445490Y656789I1394J-560D01*
G02X444619Y655298I-871J-491D01*
G01X432288D01*
G02X431302Y656462I0J1000D01*
G03X428338I-1482J247D01*
G02X427352Y655298I-986J-164D01*
G01X427237D01*
G02X426737Y655798I0J500D01*
G01Y655878D01*
X426762Y655953D01*
G03X425002Y657884I-1428J466D01*
G03X423835Y656330I332J-1465D01*
G02X422835Y655298I-1000J-32D01*
G01X416090D01*
X413291Y658097D01*
G02X413193Y659396I708J707D01*
G03X411093Y661496I-1211J889D01*
G02X409794Y661594I-592J806D01*
G01X408777Y662611D01*
G02X409484Y664318I707J707D01*
G01X412358D01*
X412758Y664718D01*
X413216D01*
G02X413716Y664218I0J-500D01*
G01Y664209D01*
G03X415719Y662787I1502J-6D01*
G02X416820Y662484I333J-943D01*
G03X419360Y664025I1154J961D01*
G01X419321Y664118D01*
Y664218D01*
G02X419821Y664718I500J0D01*
G01X420202D01*
X420320Y664649D01*
G03Y667241I760J1296D01*
G01X420202Y667172D01*
X413060D01*
G02X412562Y667633I0J500D01*
G03X409569Y667655I-1497J-117D01*
G02X408576Y666772I-993J117D01*
G01X407613D01*
X407320Y667065D01*
Y677716D01*
X405540Y679496D01*
Y695491D01*
X406082Y696034D01*
X408026Y697978D01*
Y700686D01*
X408027Y703603D01*
X414086Y709661D01*
X414866D01*
X414982Y709595D01*
G03X416499Y709607I748J1302D01*
G01X416823Y709551D01*
X424820Y701554D01*
X424896Y701355D01*
X424891Y701249D01*
Y701229D01*
G03X426467Y699673I1501J-56D01*
G01X426573Y699678D01*
X426772Y699602D01*
X427573Y698801D01*
Y698387D01*
X426511Y697325D01*
X426217Y697259D01*
G03X425506Y697395I-629J-1364D01*
G03X425019Y694506I83J-1500D01*
G03X425424Y694402I572J1389D01*
G02X426290Y693411I-134J-991D01*
G01Y693139D01*
X426157Y693005D01*
G03X425991Y692811I1054J-1070D01*
G03X426128Y690891I1219J-878D01*
G01X426203Y690705D01*
G02X426093Y690164I-464J-187D01*
G01X426085Y690156D01*
G02X425592Y690030I-353J354D01*
G03X424758Y690032I-420J-1442D01*
G03X424001Y689528I415J-1444D01*
G02X422534Y689427I-780J626D01*
G01X421738Y690222D01*
X421100Y690861D01*
Y692206D01*
X421350Y692489D01*
X421538Y692513D01*
G03X422295Y695171I-188J1490D01*
G03X420687Y695351I-945J-1168D01*
G01X420638Y695328D01*
X420516Y695298D01*
G02X420043Y695430I-119J486D01*
G01X416497Y698976D01*
G02X415685Y700356I110J994D01*
G03X414000Y702447I-1367J623D01*
G03X413336Y699842I318J-1468D01*
G02X413391Y698380I-654J-757D01*
G03X413036Y696040I1419J-1412D01*
G02X412446Y694622I-886J-463D01*
G03X412351Y694590I432J-1439D01*
G03X411424Y693561I527J-1407D01*
G01X411390Y693430D01*
X408910Y690950D01*
Y686804D01*
X409718Y685997D01*
X410639Y685076D01*
X410898D01*
G02X411230Y684929I-23J-499D01*
G01X413529Y682630D01*
X417316D01*
X421007Y678939D01*
G02X421117Y678398I-354J-354D01*
G03X422967Y676405I1393J-562D01*
G01X423004Y676417D01*
X423077Y676444D01*
X423176Y676463D01*
G02X423621Y676325I91J-492D01*
G01X424630Y675316D01*
G02X424431Y673747I-707J-707D01*
G03X424406Y671119I715J-1321D01*
G03X426648Y672438I740J1307D01*
G01Y672460D01*
G02X427148Y672960I500J0D01*
G01X430492D01*
X430776Y672676D01*
X443063D01*
X443347Y672960D01*
X445618D01*
X445838Y672842D01*
X445908Y672736D01*
G03X448414I1253J828D01*
G02X448831Y672960I417J-276D01*
G01X457875D01*
X458000Y672879D01*
G03X459640I820J1258D01*
G01X459765Y672960D01*
X470132D01*
X472010Y674838D01*
Y679574D01*
G02X472156Y679927I500J0D01*
G01X479094Y686864D01*
X479491D01*
G02X479991Y686364I0J-500D01*
G01Y686231D01*
X479900Y686071D01*
X479875Y686020D01*
G03X480061Y684420I1352J-654D01*
G03X482179Y684204I1166J946D01*
G03X482699Y685665I-952J1162D01*
G02X483679Y686864I980J199D01*
G01X484017D01*
X486351Y689198D01*
X488762D01*
G02X489730Y687946I1J-1000D01*
G03X491013Y686013I1437J-439D01*
G03X491739Y686118I155J1494D01*
G02X493120Y685194I381J-924D01*
G01Y681978D01*
G02X491758Y681046I-1000J0D01*
G03Y678266I-569J-1390D01*
G02X493120Y677334I362J-932D01*
G01Y677311D01*
G02X492804Y676846I-500J0D01*
G01X492408Y676690D01*
X492062Y676805D01*
X492004Y676845D01*
G03X489667Y675791I-847J-1241D01*
G03X491753Y674225I1490J-187D01*
G02X493120Y673295I367J-930D01*
G01Y667086D01*
X492666Y666598D01*
X492502Y666568D01*
G03X491269Y665156I268J-1478D01*
G02X490229Y664201I-999J44D01*
G03X488992Y661711I-109J-1498D01*
G02X488924Y660371I-775J-632D01*
G01X483851Y655298D01*
X483009D01*
X482579Y655553D01*
X482515Y655652D01*
G37*
G36*
G01X434600Y494681D02*
X441478Y487803D01*
X447527D01*
X448771Y486559D01*
Y484182D01*
X448179Y483590D01*
X436507D01*
X429871Y490226D01*
Y517626D01*
X430077Y517832D01*
X432597D01*
G02X432950Y517685I-1J-500D01*
G01X434600Y516035D01*
Y494681D01*
G37*
G36*
G01X449192Y181827D02*
X462027D01*
X462070Y181820D01*
G03X462588I259J1479D01*
G01X462631Y181827D01*
X464531D01*
G02X465031Y181327I0J-500D01*
G01Y153327D01*
G02X464531Y152827I-500J0D01*
G01X444531D01*
G02X444031Y153327I0J500D01*
G01Y181327D01*
G02X444531Y181827I500J0D01*
G01X445423D01*
X449192D01*
G37*
G36*
G01X584904Y116683D02*
G03X582780Y118807I-1075J1049D01*
G02X581395Y118797I-698J716D01*
G01X572999Y127193D01*
G02X572866Y127501I366J341D01*
G01Y130154D01*
X576830Y134118D01*
Y151072D01*
X576150Y151752D01*
Y190886D01*
X569518Y197518D01*
X546003D01*
G03X542997I-1503J-18D01*
G01X540606D01*
G03X538394I-1106J-1018D01*
G01X534580D01*
G03X532368I-1106J-1018D01*
G01X526071D01*
G02X525084Y198355I0J1000D01*
G03X522102I-1491J-184D01*
G02X521115Y197518I-987J163D01*
G01X506680D01*
X502910Y193748D01*
Y185845D01*
X507928Y180828D01*
X525829D01*
X526648Y181647D01*
X531298D01*
G02X532295Y180727I0J-1000D01*
G03X532300Y180636I1502J37D01*
G03X532304Y180597I1496J134D01*
G03X532320Y180489I1493J166D01*
G03X532369Y180297I1477J275D01*
G03X532371Y180292I1391J553D01*
G03X532601Y179855I1426J472D01*
G02X532461Y178550I-820J-572D01*
G03X532251Y176589I1021J-1101D01*
G03X533857Y175994I1232J860D01*
G03X533966Y176027I-380J1453D01*
G03X534971Y177241I-483J1422D01*
G03X534940Y177815I-1488J207D01*
G03X534918Y177893I-1456J-369D01*
G03X534679Y178358I-1435J-444D01*
G02X534819Y179663I820J572D01*
G03X534933Y179781I-1022J1101D01*
G03X535166Y180146I-1136J982D01*
G03X535299Y180727I-1369J619D01*
G02X536296Y181647I997J-80D01*
G01X542378D01*
X544293Y179732D01*
G02X544440Y179379I-353J-354D01*
G01Y174005D01*
X535350Y164915D01*
X509650D01*
X504643Y159908D01*
X503068D01*
G02X502213Y161428I-1J1000D01*
G03X499713I-1250J833D01*
G02X498858Y159908I-854J-520D01*
G01X490221D01*
G02X489254Y161164I0J1000D01*
G01X489565Y161459D01*
G02X489944Y161594I343J-364D01*
G01X489965Y161593D01*
X489974Y161592D01*
G03X490653Y161678I156J1494D01*
G03X491512Y163675I-523J1408D01*
G03X488674Y163457I-1382J-589D01*
G02X487724Y162737I-960J280D01*
G01X487707D01*
G03X486896Y162477I34J-1502D01*
G01X486895Y162476D01*
G02X486261Y162537I-280J414D01*
G01X484058Y164740D01*
Y180011D01*
X484164Y180147D01*
G03Y181995I-1184J924D01*
G01X484058Y182131D01*
Y187149D01*
G02X485582Y188000I1000J-1D01*
G03Y190558I788J1279D01*
G02X484058Y191409I-524J852D01*
G01Y203526D01*
G02X485765Y204233I1000J0D01*
G01X486529Y203469D01*
X486563Y203338D01*
G03X488395Y205170I1454J378D01*
G01X488264Y205204D01*
X484058Y209410D01*
Y211611D01*
X485703Y213256D01*
G02X486334Y213319I354J-353D01*
G03X487142Y213066I835J1249D01*
G03X488590Y214083I26J1502D01*
G01X493224Y218717D01*
X496433D01*
G02X497409Y217499I0J-1000D01*
G03X500341I1466J-327D01*
G02X501317Y218717I976J218D01*
G01X509695D01*
G02X510680Y217545I0J-1000D01*
G03X510662Y217182I1480J-255D01*
G03X513658I1498J-109D01*
G03X513640Y217545I-1498J108D01*
G02X514625Y218717I985J172D01*
G01X531202D01*
X540054Y227568D01*
X545466D01*
X547641Y225394D01*
X553329D01*
X558835Y230900D01*
G02X559618Y230803I354J-353D01*
G02X559758Y230235I-858J-513D01*
G03X562713Y229780I1500J-82D01*
G02X563592Y230527I968J-249D01*
G03X563733Y230542I-88J1500D01*
G02X564807Y229858I123J-992D01*
G03X565853Y228834I1441J425D01*
G03X567700Y229898I395J1449D01*
G02X569112Y230501I958J-289D01*
G03X570067Y230305I763J1294D01*
G03X570364Y230375I-194J1489D01*
G03X570892Y230691I-491J1419D01*
G03X571108Y230939I-1018J1104D01*
G01X571110Y230942D01*
X571185Y231047D01*
X571606Y231290D01*
X574286D01*
X574732Y231004D01*
X574793Y230894D01*
G03X577417I1312J732D01*
G01X577478Y231004D01*
X577697Y231145D01*
G02X578428Y230919I270J-421D01*
G01X578571Y230581D01*
X578466Y230245D01*
X578432Y230191D01*
G03X579645Y227894I1274J-796D01*
G03X581110Y229932I62J1501D01*
G02X582043Y231290I934J358D01*
G01X583085D01*
G02X584084Y230245I0J-1000D01*
G03X587074I1495J-150D01*
G02X588073Y231290I999J45D01*
G01X589208D01*
G02X590207Y230244I0J-1000D01*
G03X593207I1500J-82D01*
G02X594206Y231290I999J46D01*
G01X620530D01*
X638014Y248774D01*
X638688D01*
G03X638706Y248766I619J1368D01*
G03X640771Y249635I644J1357D01*
G03X640850Y250046I-1421J486D01*
G03X640647Y250880I-1500J77D01*
G02X640725Y251485I432J252D01*
G01X683018Y293778D01*
Y336502D01*
X718060Y371544D01*
Y451628D01*
X718370Y451938D01*
X728628D01*
X730878Y454188D01*
X736129D01*
X740470Y458530D01*
Y462880D01*
X738850Y464500D01*
X738819Y464645D01*
G03X738470Y465330I-1468J-317D01*
G03X737540Y465820I-1121J-1000D01*
G03X735873Y464603I-190J-1490D01*
G03X735864Y464108I1477J-274D01*
G03X736001Y463669I1486J223D01*
G03X736364Y463039I1349J358D01*
G01X737169Y462234D01*
G02X736673Y461164I-981J-195D01*
G03X736247Y460842I678J-1340D01*
G03X736072Y460612I1102J-1020D01*
G03X735896Y460201I1277J-790D01*
G01X735862Y460070D01*
X734380Y458588D01*
X728966D01*
G02X728128Y460059I45J1000D01*
G03X726375Y462246I-1298J756D01*
G02X725870Y462369I-151J477D01*
G02Y463077I353J354D01*
G01X726501Y463707D01*
X726677Y463883D01*
X726808Y463917D01*
G03X724976Y465749I-378J1454D01*
G01X724942Y465618D01*
X721608Y462284D01*
X718560D01*
G02X718060Y462784I0J500D01*
G01Y469391D01*
X719617Y470948D01*
X719748Y470982D01*
G03X718762Y473810I-378J1454D01*
G01X718666Y473767D01*
X718560D01*
G02X718060Y474267I0J500D01*
G01Y474518D01*
X720387Y476845D01*
X720518Y476879D01*
G03X721274Y477348I-378J1454D01*
G03X721311Y477393I-1141J976D01*
G03X719463Y479674I-1171J940D01*
G02X718060Y480590I-403J916D01*
G01Y481370D01*
X718519Y481859D01*
X718684Y481887D01*
G03X719509Y482322I-253J1481D01*
G03X719542Y482357I-1076J1048D01*
G03X719682Y482536I-1110J1012D01*
G03X719694Y482555I-1264J811D01*
G02X720818Y482955I831J-556D01*
G03X722301Y485492I472J1426D01*
G03X721966Y485723I-1013J-1110D01*
G03X720027Y485194I-676J-1342D01*
G02X718903Y484794I-831J556D01*
G03X718842Y484813I-477J-1424D01*
G03X718684Y484849I-412J-1445D01*
G01X718519Y484877D01*
X718060Y485366D01*
Y489380D01*
G02X719485Y490285I1000J0D01*
G03Y492979I665J1347D01*
G02X718060Y493884I-425J905D01*
G01Y513270D01*
G02X719156Y514265I1000J0D01*
G03Y517249I176J1492D01*
G02X718060Y518244I-96J995D01*
G01Y526889D01*
X710890Y534059D01*
X706835D01*
X706768Y534078D01*
G03X705954I-407J-1446D01*
G01X705887Y534059D01*
X696399D01*
G02X695494Y535484I0J1000D01*
G03X692806I-1344J671D01*
G02X691901Y534059I-905J-425D01*
G01X691613D01*
G02X691113Y534559I0J500D01*
G01Y534732D01*
X691220Y534868D01*
G03X691436Y535242I-1179J930D01*
G03X688961Y536842I-1395J556D01*
G03X688546Y535950I1079J-1045D01*
G03X688609Y535340I1494J-154D01*
G02X687649Y534059I-960J-281D01*
G01X686968D01*
G02X686030Y535404I0J1000D01*
G03X683210I-1410J519D01*
G02X682272Y534059I-938J-345D01*
G01X669538D01*
G02X668544Y535165I0J1000D01*
G03X668487Y535762I-1494J159D01*
G03X668219Y536267I-1437J-439D01*
G03X668040Y536453I-1168J-944D01*
G01X668039Y536454D01*
G02X667870Y536829I331J375D01*
G01Y610228D01*
X668559Y610917D01*
G02X669916Y610971I708J-707D01*
G03X672039Y613094I1024J1099D01*
G02X672093Y614451I761J649D01*
G01X677140Y619498D01*
X710166D01*
X710519Y619348D01*
X710584Y619287D01*
G03X712640I1028J1096D01*
G01X712705Y619348D01*
X713058Y619498D01*
X713745D01*
G02X714128Y619319I0J-500D01*
G03X716435I1153J963D01*
G02X716818Y619498I383J-321D01*
G01X718706D01*
X719031Y619373D01*
G03X721072Y619372I1021J1107D01*
G01X721398Y619498D01*
X764366D01*
X775420Y608444D01*
Y310607D01*
X756300Y291487D01*
Y176621D01*
X767500Y165421D01*
Y35200D01*
X764800Y32500D01*
X752286D01*
G03X747650I-2318J-3139D01*
G01X742286D01*
G03X737650I-2318J-3139D01*
G01X711942D01*
G02X711532Y32714I0J500D01*
G03X705790I-2871J-2006D01*
G02X705380Y32500I-410J286D01*
G01X680852D01*
X680798Y32512D01*
G03X679128I-835J-3709D01*
G01X679074Y32500D01*
X670852D01*
X670798Y32512D01*
G03X669128I-835J-3709D01*
G01X669074Y32500D01*
X660852D01*
X660798Y32512D01*
G03X659128I-835J-3709D01*
G01X659074Y32500D01*
X650852D01*
X650798Y32512D01*
G03X649128I-835J-3709D01*
G01X649074Y32500D01*
X640852D01*
X640798Y32512D01*
G03X639128I-835J-3709D01*
G01X639074Y32500D01*
X618260D01*
X618206Y32512D01*
G03X616536I-835J-3709D01*
G01X616482Y32500D01*
X608260D01*
X608206Y32512D01*
G03X606536I-835J-3709D01*
G01X606482Y32500D01*
X598260D01*
X598206Y32512D01*
G03X596536I-835J-3709D01*
G01X596482Y32500D01*
X588260D01*
X588206Y32512D01*
G03X586536I-835J-3709D01*
G01X586482Y32500D01*
X578260D01*
X578206Y32512D01*
G03X576536I-835J-3709D01*
G01X576482Y32500D01*
X555669D01*
X555615Y32512D01*
G03X553945I-835J-3709D01*
G01X553891Y32500D01*
X545669D01*
X545615Y32512D01*
G03X543945I-835J-3709D01*
G01X543891Y32500D01*
X535669D01*
X535615Y32512D01*
G03X533945I-835J-3709D01*
G01X533891Y32500D01*
X525669D01*
X525615Y32512D01*
G03X523945I-835J-3709D01*
G01X523891Y32500D01*
X515669D01*
X515615Y32512D01*
G03X513945I-835J-3709D01*
G01X513891Y32500D01*
X510600D01*
X506860Y36240D01*
Y97728D01*
G02X508298Y98627I1000J0D01*
G03Y101329I657J1351D01*
G02X506860Y102228I-438J899D01*
G01Y103877D01*
X510480Y107497D01*
G02X511855Y107535I708J-707D01*
G03X513978Y109658I1023J1100D01*
G02X514016Y111033I745J667D01*
G01X514733Y111750D01*
G02X515218Y111879I354J-354D01*
G01X515361Y111839D01*
X515413Y111810D01*
G03X517470Y113829I733J1311D01*
G03X517428Y113904I-1330J-696D01*
G01X517338Y114052D01*
X517379Y114396D01*
X523591Y120608D01*
X563320D01*
X565751Y123039D01*
G02X566459I354J-353D01*
G01X583681Y105817D01*
G02X583814Y105500I-367J-340D01*
G01Y82492D01*
X584431Y81874D01*
X587978Y78327D01*
X588052Y78097D01*
X588022Y77916D01*
X588015Y77888D01*
G03X590152Y80025I2984J-847D01*
G01X590124Y80018D01*
X590060Y80007D01*
G02X589627Y80148I-79J494D01*
G01X586399Y83376D01*
G02X586266Y83677I366J341D01*
G01Y86705D01*
G02X587120Y87059I500J0D01*
G01X587978Y86201D01*
X588052Y85971D01*
X588022Y85790D01*
X588015Y85762D01*
G03X590152Y87899I2984J-847D01*
G01X590124Y87892D01*
X590060Y87881D01*
G02X589627Y88022I-79J494D01*
G01X588183Y89466D01*
G02X588036Y89819I353J354D01*
G01Y90160D01*
G02X588536Y90660I500J0D01*
G01X588734D01*
X588878Y90525D01*
G03X593994Y91981I2121J2264D01*
G03X593653Y94395I-2995J808D01*
G03X589583Y95549I-2654J-1606D01*
G03X589515Y95513I1417J-2759D01*
G02X588036Y96336I-480J878D01*
G01Y96517D01*
G02X588999Y97462I999J-55D01*
G03X590398Y98590I-56J1501D01*
G02X591776Y99253I968J-249D01*
G03X591783Y99250I595J1378D01*
G03X592180Y99136I609J1373D01*
G03X592364Y99121I214J1487D01*
G03X592725Y99158I28J1502D01*
G02X593872Y98446I184J-983D01*
G03X596227Y97658I1446J407D01*
G03X596410Y97822I-908J1197D01*
G03X596797Y99118I-1092J1032D01*
G03X594985Y100319I-1479J-264D01*
G02X593838Y101031I-184J983D01*
G03X593815Y101105I-1446J-409D01*
G02X594397Y102356I947J320D01*
G03X594613Y102461I-547J1399D01*
G03X595328Y104025I-763J1294D01*
G01X595324Y104046D01*
X595319Y104093D01*
G02X595536Y104555I498J48D01*
G01X595700Y104666D01*
G02X596335Y104606I281J-413D01*
G01X596798Y104143D01*
G02X596903Y102900I-726J-687D01*
G03X599000Y100803I1220J-877D01*
G02X600243Y100698I556J-831D01*
G01X603550Y97391D01*
G02X603523Y95989I-726J-687D01*
G03X603414Y95877I1020J-1102D01*
G03X603288Y95712I1128J-992D01*
G02X602035Y95397I-813J583D01*
G03X600342Y95139I-661J-1349D01*
G03X600172Y93147I1032J-1091D01*
G03X600173Y93146I1063J1062D01*
G03X600966Y92602I1201J901D01*
G02X601659Y91631I-307J-952D01*
G03X601812Y90868I1499J-96D01*
G03X602134Y90436I1346J667D01*
G03X603750Y90154I1024J1099D01*
G02X605144Y89290I395J-919D01*
G01Y85820D01*
X611796Y79167D01*
X612551Y78412D01*
G02X612691Y77980I-354J-353D01*
G01X612680Y77916D01*
X612673Y77888D01*
G03X614810Y80025I2984J-847D01*
G01X614782Y80018D01*
X614718Y80007D01*
G02X614285Y80148I-79J494D01*
G01X607729Y86704D01*
G02X607596Y87005I366J341D01*
G01Y88882D01*
G02X609269Y89568I999J-54D01*
G01X610644Y88194D01*
X611842Y86995D01*
X612551Y86286D01*
G02X612691Y85854I-354J-353D01*
G01X612680Y85787D01*
X612672Y85760D01*
G03X612655Y85697I2986J-840D01*
G01X612651Y85681D01*
G03X612650Y85675I3059J-513D01*
G03X614954Y81894I3007J-760D01*
G03X616294Y81879I704J3021D01*
G03X615982Y88000I-634J3036D01*
G03X615757Y88015I-319J-3085D01*
G03X614784Y87892I-102J-3100D01*
G02X614289Y88018I-141J480D01*
G01X609789Y92518D01*
G02X609656Y92835I367J340D01*
G01Y96954D01*
X595530Y111080D01*
X589287D01*
G02X588979Y111213I33J499D01*
G01X584894Y115298D01*
G02X584904Y116683I726J687D01*
G37*
G36*
G01X492654Y231119D02*
G03X490463Y233043I-1334J690D01*
G03X490035Y232587I857J-1233D01*
G01X490004Y232535D01*
X489961Y232492D01*
G02X489254I-354J354D01*
G01X488910Y232836D01*
Y241129D01*
X489105Y241394D01*
X489262Y241443D01*
G03Y244311I-446J1434D01*
G02X488910Y244789I148J478D01*
G01Y330325D01*
X502966Y344381D01*
X503030D01*
X507408Y348759D01*
X598561D01*
X602939Y344381D01*
X606041D01*
X606279Y344238D01*
X606344Y344115D01*
G03X608998I1327J703D01*
G01X609063Y344238D01*
X609301Y344381D01*
X626511D01*
X626749Y344238D01*
X626814Y344115D01*
G03X629468I1327J703D01*
G02X629910Y344381I442J-234D01*
G01X657760D01*
X663660Y338481D01*
Y311544D01*
G02X663160Y311044I-500J0D01*
G01X662901D01*
X662411Y311527D01*
X662390Y311700D01*
G03X659408I-1491J-185D01*
G01X659387Y311527D01*
X658897Y311044D01*
X651908D01*
X643800Y302936D01*
X625411D01*
X622980Y305367D01*
Y316205D01*
X613120Y326065D01*
X609818D01*
G03X609785Y326066I-62J-1500D01*
G01X603451D01*
G02X602951Y326551I0J500D01*
G03X599949I-1501J-42D01*
G02X599449Y326066I-500J15D01*
G01X593286D01*
G03X593279Y326065I280J-1982D01*
G01X588689D01*
G03X588682Y326066I-287J-1981D01*
G01X588286D01*
G03X588279Y326065I280J-1982D01*
G01X583689D01*
G03X583682Y326066I-287J-1981D01*
G01X519615D01*
G03X519582Y326065I29J-1501D01*
G01X518993D01*
X518572Y325644D01*
G03X518553Y325625I1052J-1071D01*
G01X518552D01*
X507154Y314226D01*
Y285477D01*
X506929Y285202D01*
X506753Y285166D01*
G03Y277910I736J-3628D01*
G02X507154Y277420I-99J-490D01*
G01Y244238D01*
X509520Y241871D01*
X510808Y240583D01*
X526268D01*
X528088Y238763D01*
X534611D01*
G02X535077Y238446I1J-500D01*
G01Y238445D01*
G03X537275Y237721I1399J548D01*
G03X537429Y237832I-800J1272D01*
G03X537886Y238475I-953J1161D01*
G01X537924Y238579D01*
X538738Y239393D01*
X550641D01*
X553570Y236464D01*
Y229277D01*
X552262Y227968D01*
X548708D01*
X546533Y230144D01*
X538796D01*
X538326Y229674D01*
X538322D01*
X538085Y229438D01*
X534873D01*
X534803Y229368D01*
X534573Y229294D01*
X534454Y229314D01*
G03X532726Y227587I-246J-1482D01*
G01X532746Y227467D01*
X532672Y227237D01*
X532258Y226823D01*
X522068D01*
X519618Y229273D01*
X517896D01*
G03X515354I-1271J802D01*
G01X506178D01*
X505765Y229686D01*
X493556D01*
G02X492654Y231119I0J1000D01*
G37*
G36*
G01X610912Y238859D02*
G02X610270Y239858I356J934D01*
G03X610276Y239965I-1496J138D01*
G03X610259Y240222I-1502J30D01*
G03X607614Y240950I-1485J-226D01*
G03X607317Y239630I1160J-954D01*
G03X607383Y239429I1456J367D01*
G02X606439Y238095I-943J-334D01*
G01X606437D01*
G02X605976Y238401I0J500D01*
G01X605807Y238805D01*
X605911Y239140D01*
X605946Y239196D01*
G03X603954Y241313I-1272J799D01*
G03X603546Y240987I719J-1318D01*
G03X603482Y240909I1129J-991D01*
G02X601983Y240808I-794J608D01*
G03X599765I-1109J-1013D01*
G02X598266Y240909I-705J709D01*
G03X598144Y241049I-1191J-915D01*
G03X596968Y241493I-1070J-1054D01*
G03X596188Y241208I105J-1498D01*
G02X594759Y241533I-564J826D01*
G03X592893Y242171I-1299J-753D01*
G03X593774Y239311I566J-1391D01*
G03X594345Y239567I-316J1469D01*
G02X595774Y239242I564J-826D01*
G03X595835Y239145I1301J751D01*
G01X595874Y239088D01*
X595919Y238956D01*
G02X595605Y238322I-474J-160D01*
G01X595511Y238290D01*
G03X595310Y238296I-145J-1495D01*
G03X594718Y238146I65J-1501D01*
G01X594614Y238095D01*
X591890D01*
X589321Y235526D01*
X558765D01*
X553777Y240514D01*
X546940D01*
X546931Y240523D01*
X538997D01*
G02X538187Y242111I-1J1000D01*
G03X535757I-1215J882D01*
G02X534947Y240523I-809J-588D01*
G01X532218D01*
X529868Y242873D01*
X509935D01*
X508655Y244153D01*
X508156Y244653D01*
Y272225D01*
X508181Y272302D01*
G03X508281Y273017I-1900J630D01*
G01X508156Y273142D01*
Y276776D01*
X508189Y276810D01*
G02X508156Y277037I966J256D01*
G01Y277669D01*
X508356Y277935D01*
X508517Y277982D01*
G03Y285094I-1028J3556D01*
G01X508356Y285141D01*
X508156Y285407D01*
Y313811D01*
X519261Y324917D01*
G02X519615Y325064I354J-353D01*
G01X583664D01*
G02X584572Y323759I-45J-999D01*
G03X584510Y323532I1413J-508D01*
G03X584503Y323495I1472J-298D01*
G02X583643Y322703I-980J201D01*
G03X582762Y320061I94J-1499D01*
G03X585147Y320688I975J1143D01*
G03X585218Y320955I-1410J518D01*
G02X586078Y321747I980J-201D01*
G03X587383Y322699I-94J1499D01*
G03X587396Y323759I-1399J547D01*
G02X588304Y325064I953J306D01*
G01X588664D01*
G02X589572Y323759I-45J-999D01*
G03X592396I1412J-513D01*
G02X593304Y325064I953J306D01*
G01X601036D01*
X601095Y325049D01*
G03X601805I355J1460D01*
G01X601864Y325064D01*
X609785D01*
G02X610139Y324917I0J-500D01*
G01X620131Y314924D01*
Y302997D01*
X622985Y300143D01*
X630264D01*
X630609Y300000D01*
X630673Y299944D01*
G03X632671I999J1122D01*
G01X632735Y300000D01*
X633080Y300143D01*
X644695D01*
X649470Y304918D01*
Y305453D01*
X653800Y309783D01*
X672873D01*
X677530Y305126D01*
Y291009D01*
X639492Y252971D01*
X633917D01*
X619041Y238095D01*
X611929D01*
X611713Y238207D01*
X611642Y238307D01*
Y238308D01*
G03X610912Y238859I-1227J-867D01*
G37*
G36*
G01X498768Y420120D02*
Y432011D01*
G02X499268Y432511I500J0D01*
G01X508757D01*
X508857Y432465D01*
G03X510115I629J1364D01*
G01X510215Y432511D01*
X518000D01*
G02X518500Y432011I0J-500D01*
G01Y420120D01*
G02X518000Y419620I-500J0D01*
G01X499268D01*
G02X498768Y420120I0J500D01*
G37*
G36*
G01X555787Y533265D02*
G02X555291Y533140I-353J354D01*
G03X553421Y531270I-431J-1439D01*
G01X553461Y531138D01*
X553393Y530871D01*
X551074Y528552D01*
X550753Y528502D01*
X550608Y528577D01*
G03X548585Y526554I-688J-1335D01*
G01X548660Y526409D01*
X548610Y526088D01*
X547446Y524924D01*
X503350D01*
G02X502850Y525424I0J500D01*
G01Y526905D01*
G02X503893Y527904I1000J0D01*
G03Y530906I65J1501D01*
G02X502850Y531905I-43J999D01*
G01Y537766D01*
G02X503689Y538753I1000J0D01*
G03X504948Y540318I-241J1483D01*
G02X505855Y541369I998J55D01*
G03X505756Y544367I-137J1496D01*
G02X504804Y545150I24J1000D01*
G03X503347Y546327I-1466J-325D01*
G02X502850Y546827I3J500D01*
G01Y547823D01*
G02X503347Y548323I500J0D01*
G03X504376Y550911I-9J1502D01*
G02X504360Y552341I691J723D01*
G01X505144Y553124D01*
X505382D01*
Y553362D01*
X506910Y554891D01*
Y586606D01*
X505382Y588134D01*
Y588442D01*
X503106Y590717D01*
G02X502960Y591070I354J353D01*
G01Y595603D01*
X505109Y597752D01*
X556853D01*
X557550Y597055D01*
Y535028D01*
X555787Y533265D01*
G37*
G36*
G01X521803Y430587D02*
G03X521110Y432777I576J1387D01*
G02X519558Y432605I-845J535D01*
G01X517278Y434885D01*
X517262D01*
X516898Y435046D01*
X516833Y435110D01*
G03X515528Y435520I-1053J-1071D01*
G02X514360Y436505I-168J986D01*
G01Y443513D01*
X514362Y443537D01*
Y443539D01*
G03Y443819I-1495J140D01*
G01Y443821D01*
X514360Y443845D01*
Y449635D01*
G02X514860Y450135I500J0D01*
G01X538548D01*
X539168Y450754D01*
Y460575D01*
X540469Y461876D01*
G02X541800Y461950I707J-707D01*
G03X544238Y463055I938J1173D01*
G02X545237Y464009I999J-46D01*
G01X546001D01*
G02X546501Y463509I0J-500D01*
G01Y463351D01*
X546410Y463221D01*
G03X549088Y462748I1228J-865D01*
G02X550053Y464009I965J261D01*
G01X570611D01*
G02X571067Y463714I0J-500D01*
G01X571068Y463712D01*
G03X571285Y463363I1372J611D01*
G01X571400Y463225D01*
Y448434D01*
X552694Y429728D01*
X552621Y429692D01*
G03X552188Y429358I639J-1276D01*
G01X552178Y429346D01*
X538886Y416054D01*
X524273D01*
G02X523920Y416200I0J500D01*
G01X520420Y419701D01*
Y429663D01*
G02X521803Y430587I1000J0D01*
G37*
G36*
G01X512045Y453478D02*
Y453479D01*
Y473352D01*
G02X512545Y473852I500J0D01*
G01X534280D01*
G02X534780Y473352I0J-500D01*
G01Y451873D01*
G02X534280Y451373I-500J0D01*
G01X517462D01*
X512868D01*
X512045Y452196D01*
Y453478D01*
G37*
G36*
G01X545910Y623191D02*
Y633541D01*
G02X546410Y634041I500J0D01*
G01X559803D01*
X560054Y633790D01*
Y622797D01*
X559947Y622690D01*
X546411D01*
X545910Y623191D01*
G37*
G36*
G01X663468Y341582D02*
X657730Y347320D01*
X641842D01*
G02X641041Y348919I0J1000D01*
G03X638635I-1203J899D01*
G02X637834Y347320I-801J-599D01*
G01X604230D01*
X597310Y354240D01*
Y368718D01*
X599324Y370732D01*
X670188D01*
X674148Y374692D01*
G02X675746Y374440I707J-707D01*
G03X677071Y373622I1337J684D01*
G02X678058Y372722I-8J-1000D01*
G03X679564Y374375I1494J151D01*
G02X678577Y375275I8J1000D01*
G03X676493Y376505I-1494J-151D01*
G02X675100Y377425I-393J920D01*
G01Y377899D01*
G02X675259Y378265I500J0D01*
G03Y380463I-1024J1099D01*
G02X675100Y380829I341J366D01*
G01Y414288D01*
G02X675600Y414788I500J0D01*
G01X684268D01*
G02X685252Y413613I0J-1000D01*
G03X686693Y411847I1479J-264D01*
G02X687180Y411348I-13J-500D01*
G01Y408957D01*
G02X686790Y408469I-500J0D01*
G03X685696Y406528I331J-1465D01*
G02X685192Y405316I-948J-316D01*
G03X686052Y402480I666J-1346D01*
G02X687180Y401489I128J-992D01*
G01Y399524D01*
G02X686681Y399024I-500J0D01*
G03Y396020I5J-1502D01*
G02X687180Y395520I-1J-500D01*
G01Y394524D01*
G02X686681Y394024I-500J0D01*
G03Y391020I5J-1502D01*
G02X687180Y390520I-1J-500D01*
G01Y388271D01*
X687073Y388059D01*
X686977Y387988D01*
G03Y385572I892J-1208D01*
G02X687180Y385169I-297J-402D01*
G01Y382436D01*
G02X687039Y382088I-500J0D01*
G03Y379998I1079J-1045D01*
G02X687180Y379650I-359J-348D01*
G01Y345202D01*
X683560Y341582D01*
X663468D01*
G37*
G36*
G01X627372Y572111D02*
G02X626372Y573124I0J1000D01*
G03X624147Y574460I-1502J19D01*
G01X624001Y574379D01*
X623672Y574426D01*
X623184Y574914D01*
G02X623044Y575350I353J354D01*
G01X623707Y579308D01*
X623269Y584534D01*
X617017Y602122D01*
X616390Y602800D01*
Y611591D01*
X613882Y614099D01*
X613866Y614279D01*
G03X611700Y615487I-1496J-136D01*
G01X611595Y615435D01*
X610748D01*
X609100Y617083D01*
Y622790D01*
X609470Y623160D01*
X617661D01*
X618940Y624439D01*
Y626582D01*
X619870Y627512D01*
X623036D01*
X623156Y627439D01*
G03X624724I784J1281D01*
G01X624844Y627512D01*
X628689D01*
X628828Y627398D01*
G03X629253Y627153I953J1161D01*
G02X629734Y625662I-351J-936D01*
G03X630825Y626323I1250J-833D01*
G02X630525Y627254I-52J497D01*
G03X630734Y627398I-745J1304D01*
G01X630873Y627512D01*
X635091D01*
X635381Y627234D01*
X635389Y627033D01*
G03X638391I1501J62D01*
G02X638890Y627512I499J-21D01*
G01X642649D01*
G02X643145Y627073I0J-500D01*
G03X646127I1491J184D01*
G02X646623Y627512I496J-61D01*
G01X651525D01*
X657220Y621817D01*
Y618018D01*
G02X656081Y617027I-1000J-1D01*
G03X654877Y614415I-208J-1488D01*
G02X654927Y613717I-331J-375D01*
G03X656160Y611244I1143J-974D01*
G02X657220Y610246I60J-998D01*
G01Y604206D01*
G02X656007Y603229I-1000J0D01*
G03Y600293I-319J-1468D01*
G02X657220Y599316I213J-977D01*
G01Y594297D01*
G02X655910Y593346I-1000J0D01*
G03Y590490I-465J-1428D01*
G02X657220Y589539I310J-951D01*
G01Y577781D01*
X651550Y572111D01*
X638446D01*
G02X638057Y572296I-1J500D01*
G03X635723I-1167J-945D01*
G01X635651Y572208D01*
X635448Y572111D01*
X627372D01*
G37*
G36*
G01X657279Y375020D02*
X654384D01*
G02X653487Y376462I0J1000D01*
G03X650791I-1348J663D01*
G02X649894Y375020I-897J-442D01*
G01X621961D01*
G02X621461Y375520I0J500D01*
G01Y416381D01*
X625840Y420760D01*
X670355D01*
X670451Y420718D01*
G03X670666Y420642I606J1373D01*
G01X670795Y420608D01*
X671700Y419703D01*
Y410645D01*
G02X670196Y409781I-1000J0D01*
G03Y407185I-756J-1298D01*
G02X671700Y406321I504J-864D01*
G01Y405000D01*
G02X670236Y404114I-1000J0D01*
G03Y401452I-696J-1331D01*
G02X671700Y400566I464J-886D01*
G01Y397345D01*
G02X670196Y396481I-1000J0D01*
G03Y393885I-756J-1298D01*
G02X671700Y393021I504J-864D01*
G01Y388500D01*
G02X670236Y387614I-1000J0D01*
G03Y384952I-696J-1331D01*
G02X671700Y384066I464J-886D01*
G01Y375520D01*
G02X671200Y375020I-500J0D01*
G01X664675D01*
G02X663762Y376427I0J1000D01*
G03X661436Y378199I-1372J612D01*
G03X661339Y378112I953J-1161D01*
G02X660628Y378124I-350J358D01*
G03X658042Y377047I-1085J-1038D01*
G03X658184Y376446I1501J37D01*
G02X657279Y375020I-905J-426D01*
G37*
G36*
G01X625340Y563591D02*
Y554731D01*
X650850D01*
Y563591D01*
X625340D01*
G37*
%LPC*%
G75*
G36*
G01X174489Y790795D02*
G03Y789595I800J-600D01*
G02X172085I-1202J-900D01*
G03Y790795I-800J600D01*
G02X174489I1202J900D01*
G37*
G36*
G01X142993D02*
G03Y789595I800J-600D01*
G02X140589I-1202J-900D01*
G03Y790795I-800J600D01*
G02X142993I1202J900D01*
G37*
G36*
G01X83938D02*
G03Y789595I800J-600D01*
G02X81534I-1202J-900D01*
G03Y790795I-800J600D01*
G02X83938I1202J900D01*
G37*
G36*
G01X72127D02*
G03Y789595I800J-600D01*
G02X69723I-1202J-900D01*
G03Y790795I-800J600D01*
G02X72127I1202J900D01*
G37*
G36*
G01X136620Y783409D02*
G03X136585Y782704I336J-370D01*
G02X134460Y782809I-1115J-1007D01*
G03X134495Y783514I-336J370D01*
G02X136620Y783409I1115J1007D01*
G37*
G36*
G01X137130Y726511D02*
G03X136204Y725771I40J-999D01*
G02X134693Y727662I-1451J390D01*
G03X135619Y728402I-40J999D01*
G02X137130Y726511I1451J-390D01*
G37*
G36*
G01X134476Y701306D02*
G02X132521Y702879I0J2002D01*
G03X132134Y703262I-488J-106D01*
G02X130947Y704548I304J1471D01*
G03X130587Y704967I-496J-62D01*
G02X129130Y706893I545J1926D01*
G01Y717404D01*
X129939Y718212D01*
X160929D01*
X161738Y717403D01*
Y704985D01*
X158060Y701306D01*
X134476D01*
G37*
G36*
G01X108424Y712215D02*
G02X102287Y684698I-9996J-12213D01*
G02X88461Y712239I-3861J15302D01*
G03X89142Y713711I-1253J1473D01*
G01Y719686D01*
G02X107714I9286J0D01*
G01Y713711D01*
G03X108424Y712215I1934J2D01*
G37*
G36*
G01X62447Y619867D02*
G03X62369Y620576I-387J316D01*
G02X61813Y621540I931J1179D01*
G03X60976Y622386I-990J-142D01*
G02X62692Y624085I229J1484D01*
G03X63529Y623239I990J142D01*
G02X64463Y620805I-229J-1484D01*
G03X64541Y620096I387J-316D01*
G02X62447Y619867I-931J-1179D01*
G37*
G36*
G01X97092Y787971D02*
G02X95687Y786307I88J-1499D01*
G03X94635Y787196I-994J-109D01*
G02X93345Y789595I-88J1499D01*
G03Y790795I-800J600D01*
G02X95749I1202J900D01*
G03Y789595I800J-600D01*
G02X96040Y788860I-1202J-901D01*
G03X97092Y787971I994J109D01*
G37*
G36*
G01X103417Y783316D02*
G02X101195Y781323I-997J-1124D01*
G03X99664Y781444I-816J-578D01*
G02X99816Y783362I-1074J1050D01*
G03X101347Y783241I816J578D01*
G02X101425Y783316I1080J-1045D01*
G03Y784813I-662J748D01*
G02X103638Y786819I996J1125D01*
G03X105211Y786760I810J587D01*
G02X107553Y786700I1147J-970D01*
G03X109126Y786678I795J606D01*
G02X111356Y784671I1169J-944D01*
G03Y783254I706J-709D01*
G02X109234I-1061J-1063D01*
G03Y784671I-706J709D01*
G02X109100Y784824I1060J1064D01*
G03X107527Y784846I-795J-606D01*
G02X105141Y784909I-1169J944D01*
G03X103568Y784968I-810J-587D01*
G02X103417Y784813I-1149J968D01*
G03Y783316I662J-748D01*
G37*
G36*
G01X128497Y781088D02*
G02X126022Y782787I-1207J894D01*
G03X125490Y784272I-845J535D01*
G02X125209Y784398I471J1426D01*
G03X123914Y784139I-500J-866D01*
G02X123471Y786352I-1194J912D01*
G03X124766Y786611I500J866D01*
G02X127228Y784894I1194J-912D01*
G03X127760Y783409I845J-535D01*
G02X128221Y783161I-470J-1427D01*
G03X129643Y783350I619J785D01*
G02X129854Y783580I1206J-895D01*
G03X129806Y784365I-332J374D01*
G02X131882Y784727I854J1236D01*
G03X131958Y783470I813J-582D01*
G02X129919Y781277I-1108J-1014D01*
G03X128497Y781088I-619J-785D01*
G37*
G36*
G01X140749Y782249D02*
G02X138499Y782303I-1149J-968D01*
G03X138531Y783628I-732J681D01*
G02X140781Y783574I1149J968D01*
G03X140749Y782249I732J-681D01*
G37*
G36*
G01X120364Y782095D02*
G02X118663Y781086I-274J-1477D01*
G03X117895Y782380I-950J311D01*
G02X116669Y783926I274J1477D01*
G03X116219Y784447I-500J23D01*
G02X114877Y786107I151J1494D01*
G03X114023Y787208I-994J111D01*
G02X113030Y789595I209J1487D01*
G03Y790795I-800J600D01*
G02X115434I1202J900D01*
G03Y789595I800J-600D01*
G02X115725Y788529I-1202J-901D01*
G03X116579Y787428I994J-111D01*
G02X117870Y785872I-209J-1487D01*
G03X118320Y785351I500J-23D01*
G02X119596Y783389I-151J-1494D01*
G03X120364Y782095I950J-311D01*
G37*
G36*
G01X150345Y781636D02*
G02X148249Y779528I-895J-1207D01*
G03X146698Y779588I-800J-600D01*
G02X144630Y781752I-1127J993D01*
G03X144862Y783047I-625J780D01*
G02X147238Y784856I1288J774D01*
G03X148701Y784871I725J689D01*
G02X150972Y784810I1109J-1013D01*
G03X152375Y784666I774J633D01*
G02X154801Y783248I945J-1167D01*
G03X155540Y782112I986J-167D01*
G02X153689Y780907I-370J-1456D01*
G03X152950Y782043I-986J167D01*
G02X152158Y782547I370J1456D01*
G03X150755Y782691I-774J-633D01*
G02X150434Y782492I-946J1167D01*
G03X150345Y781636I209J-454D01*
G37*
G36*
G01X172421Y781641D02*
G02X171134Y779821I179J-1491D01*
G03X170039Y780595I-976J-219D01*
G02X168623Y782938I-179J1491D01*
G03X168419Y784291I-823J568D01*
G02X170587Y784618I931J1179D01*
G03X170791Y783265I823J-568D01*
G02X171326Y782415I-931J-1179D01*
G03X172421Y781641I976J219D01*
G37*
G36*
G01X161845Y776956D02*
G02X161109Y778947I-1365J627D01*
G03X161773Y779192I210J454D01*
G02X162547Y779946I1365J-627D01*
G03X163143Y781008I-394J919D01*
G02X165221Y779841I1487J214D01*
G03X164625Y778779I394J-919D01*
G02X162509Y777201I-1487J-214D01*
G03X161845Y776956I-210J-454D01*
G37*
G36*
G01X121195Y740135D02*
G02X119217Y739867I-838J-1246D01*
G03X119203Y741185I-759J651D01*
G02X121338Y743293I1119J1002D01*
G03X122615Y743231I676J737D01*
G02X122502Y740924I903J-1200D01*
G03X121225Y740986I-676J-737D01*
G02X121187Y740959I-889J1211D01*
G03X121195Y740135I287J-409D01*
G37*
G36*
G01X133766Y732527D02*
G02X132369Y734484I-1432J455D01*
G03X133345Y735181I23J999D01*
G02X133875Y735927I1431J-456D01*
G03Y737525I-601J799D01*
G02X133735Y739807I902J1201D01*
G03X133712Y741269I-694J720D01*
G02X135762Y741301I1008J1113D01*
G03X135785Y739839I694J-720D01*
G02X135679Y737525I-1008J-1113D01*
G03Y735927I601J-799D01*
G02X134742Y733224I-902J-1201D01*
G03X133766Y732527I-23J-999D01*
G37*
G36*
G01X174150Y729673D02*
G02X173798Y727445I804J-1269D01*
G03X172493Y727651I-770J-638D01*
G02X172845Y729879I-804J1269D01*
G03X174150Y729673I770J638D01*
G37*
G36*
G01X188744Y705680D02*
G02X186820Y705653I-946J-1167D01*
G03X186798Y707189I-651J759D01*
G02X188722Y707216I946J1167D01*
G03X188744Y705680I651J-759D01*
G37*
G36*
G01X179180Y699177D02*
G02X177376I-902J-1201D01*
G03Y700775I-601J799D01*
G02Y703177I902J1201D01*
G03Y704775I-601J799D01*
G02Y707177I902J1201D01*
G03Y708775I-601J799D01*
G02X179180I902J1201D01*
G03Y707177I601J-799D01*
G02Y704775I-902J-1201D01*
G03Y703177I601J-799D01*
G02Y700775I-902J-1201D01*
G03Y699177I601J-799D01*
G37*
G36*
G01X170346Y698445D02*
G02X168267Y698519I-1078J-1046D01*
G03X168318Y699960I-667J745D01*
G02X170397Y699886I1078J1046D01*
G03X170346Y698445I667J-745D01*
G37*
G36*
G01X148906Y686580D02*
G02X148886Y688522I-1156J959D01*
G03X150411Y688538I756J655D01*
G02X150431Y686596I1156J-959D01*
G03X148906Y686580I-756J-655D01*
G37*
G36*
G01X168730Y685447D02*
G02X166698Y686313I-1415J-504D01*
G03X167230Y687560I-410J912D01*
G02X169262Y686694I1415J504D01*
G03X168730Y685447I410J-912D01*
G37*
G36*
G01X165337Y682803D02*
G02X163707Y681662I-170J-1492D01*
G03X162848Y682889I-973J233D01*
G02X162358Y683032I170J1492D01*
G03X160988Y682500I-440J-898D01*
G02X160250Y684399I-1398J550D01*
G03X161620Y684931I440J898D01*
G02X162399Y685750I1398J-550D01*
G03X162829Y687202I-411J911D01*
G02X162596Y687875I1262J814D01*
G03X161600Y687862I-497J-46D01*
G02X161287Y688883I-1499J99D01*
G03X162882Y688904I790J614D01*
G02X163613Y689438I1210J-890D01*
G03X164227Y690747I-318J948D01*
G02X166107Y689865I1401J542D01*
G03X165493Y688556I318J-948D01*
G02X164711Y686645I-1401J-542D01*
G03X164281Y685193I411J-911D01*
G02X164478Y684030I-1263J-812D01*
G03X165337Y682803I973J-233D01*
G37*
G36*
G01X135966Y680548D02*
G02X134096Y680136I-686J-1336D01*
G03X133764Y681642I-788J616D01*
G02X133249Y683880I686J1336D01*
G03X132912Y685367I-799J601D01*
G02X132398Y685807I695J1332D01*
G03X130800Y685822I-805J-593D01*
G02X130816Y687627I-1193J913D01*
G03X132414Y687612I805J593D01*
G02X134808Y685797I1193J-913D01*
G03X135145Y684310I799J-601D01*
G02X135634Y682054I-695J-1332D01*
G03X135966Y680548I788J-616D01*
G37*
G36*
G01X153121Y675964D02*
G02X150598Y674346I-1206J-895D01*
G03X149228Y674735I-877J-481D01*
G02X149804Y676763I-741J1306D01*
G03X151174Y676374I877J481D01*
G02X151205Y676392I769J-1289D01*
G03X151282Y677222I-236J440D01*
G02X153244Y677293I940J1172D01*
G03X153121Y675964I680J-733D01*
G37*
G36*
G01X161492Y675583D02*
G02X159862Y676471I-1380J-593D01*
G03X160614Y677852I-167J986D01*
G02X163495Y678379I1380J593D01*
G03X164701Y677356I999J-45D01*
G02X163511Y675953I311J-1470D01*
G03X162305Y676976I-999J45D01*
G02X162244Y676964I-320J1467D01*
G03X161492Y675583I167J-986D01*
G37*
G36*
G01X157330Y675421D02*
G02X155382Y676201I-1374J-608D01*
G03X155914Y677530I-382J924D01*
G02X155902Y678718I1373J608D01*
G03X155247Y680068I-923J386D01*
G02X157035Y680935I403J1447D01*
G03X157690Y679585I923J-386D01*
G02X157862Y676750I-403J-1447D01*
G03X157330Y675421I382J-924D01*
G37*
G36*
G01X121930Y671741D02*
G02X120114Y671667I-859J-1232D01*
G03X120049Y673258I-637J771D01*
G02X121865Y673332I859J1232D01*
G03X121930Y671741I637J-771D01*
G37*
G36*
G01X96842Y643915D02*
G02X94234Y645093I-1492J173D01*
G03X94218Y646450I-743J670D01*
G02X95788Y648905I1092J1031D01*
G03X97027Y649463I318J948D01*
G02X99558Y647909I1383J-585D01*
G03X99575Y647245I382J-322D01*
G02X98093Y644766I-1095J-1028D01*
G03X96842Y643915I-258J-966D01*
G37*
G36*
G01X60693Y642159D02*
G02X59750Y644364I-1303J747D01*
G03X60857Y644838I239J971D01*
G02X61589Y645480I1303J-747D01*
G03X62185Y646626I-379J925D01*
G02X64221Y645568I1465J331D01*
G03X63625Y644422I379J-925D01*
G02X61800Y642633I-1465J-331D01*
G03X60693Y642159I-239J-971D01*
G37*
G36*
G01X62651Y628464D02*
G02X59728Y629145I-1446J405D01*
G03X59059Y630278I-983J184D01*
G02X58994Y630301I468J1427D01*
G03X57679Y629652I-356J-935D01*
G02X56776Y631484I-1439J429D01*
G03X58091Y632133I356J935D01*
G02X60931Y631162I1440J-428D01*
G03X61713Y630594I466J-180D01*
G03X62044Y631099I-632J775D01*
G02X63564Y629193I1446J-406D01*
G03X62651Y628464I50J-999D01*
G37*
G36*
G01X50711Y620870D02*
G02X49595Y619038I340J-1463D01*
G03X48400Y619766I-969J-246D01*
G02X47219Y622474I-340J1463D01*
G03X47411Y623962I-559J829D01*
G02X48101Y626389I1129J991D01*
G03X48792Y627524I-293J956D01*
G02X50709Y626357I1478J269D01*
G03X50018Y625222I293J-956D01*
G02X49381Y623708I-1478J-269D01*
G03X49189Y622220I559J-829D01*
G02X49516Y621598I-1129J-991D01*
G03X50711Y620870I969J246D01*
G37*
G36*
G01X98333Y615197D02*
G02X96662Y612806I-542J-1400D01*
G03X95175Y612823I-751J-660D01*
G02X93847Y615326I-1105J1018D01*
G03X94698Y616319I-149J989D01*
G02X94702Y616437I1502J8D01*
G03X93851Y617500I-997J74D01*
G02X95568Y618874I219J1486D01*
G03X96419Y617811I997J-74D01*
G02X96514Y617794I-217J-1486D01*
G03X97056Y618525I104J489D01*
G02X98546Y617760I1315J727D01*
G03X97678Y616590I116J-993D01*
G02X97697Y616208I-1478J-265D01*
G03X98333Y615197I997J-78D01*
G37*
G36*
G01X16840Y612110D02*
G02X14559Y611748I-990J-1130D01*
G03X14359Y613012I-859J512D01*
G02X16640Y613374I990J1130D01*
G03X16840Y612110I859J-512D01*
G37*
G36*
G01X75556Y610406D02*
G02X73884Y608785I-176J-1492D01*
G03X73004Y609692I-996J-86D01*
G02X74676Y611313I176J1492D01*
G03X75556Y610406I996J86D01*
G37*
G36*
G01X74628Y601494D02*
G02X72982Y603094I-1498J105D01*
G03X73882Y604019I-98J995D01*
G02X75528Y602419I1498J-105D01*
G03X74628Y601494I98J-995D01*
G37*
G36*
G01X40399Y602051D02*
G02X38335Y602045I-1029J-1095D01*
G03X38331Y603498I-689J725D01*
G02X40395Y603504I1029J1095D01*
G03X40399Y602051I689J-725D01*
G37*
G36*
G01X14844Y591249D02*
G02X14283Y593227I-1334J690D01*
G03X15686Y593624I515J857D01*
G02X16247Y591646I1334J-690D01*
G03X14844Y591249I-515J-857D01*
G37*
G36*
G01X67173Y575883D02*
G02X64657Y574307I-1137J-982D01*
G03X64066Y574591I-459J-198D01*
G02X63582Y577539I-396J1449D01*
G03X64509Y578369I-59J999D01*
G02X67154Y577167I1480J-254D01*
G03X67173Y575883I776J-631D01*
G37*
G36*
G01X35317Y538013D02*
G02X33103Y537947I-1077J-1047D01*
G03X33063Y539298I-757J654D01*
G02X35277Y539364I1077J1047D01*
G03X35317Y538013I757J-654D01*
G37*
G36*
G01X80213Y231737D02*
G03X79972Y230561I663J-749D01*
G02X77618Y231044I-1358J-641D01*
G03X77859Y232220I-663J749D01*
G02X80213Y231737I1358J641D01*
G37*
G36*
G01X82215Y258791D02*
G02X80142Y258816I-1050J-1074D01*
G03X80160Y260263I-681J732D01*
G02X82233Y260238I1050J1074D01*
G03X82215Y258791I681J-732D01*
G37*
G36*
G01X43579Y180424D02*
G02X40281I-1649J-2203D01*
G03Y182026I-599J801D01*
G02Y186432I1649J2203D01*
G03Y188034I-599J801D01*
G02Y192440I1649J2203D01*
G03Y194042I-599J801D01*
G02Y198448I1649J2203D01*
G03Y200050I-599J801D01*
G02Y204456I1649J2203D01*
G03Y206057I-600J800D01*
G02Y210463I1649J2203D01*
G03Y212065I-599J801D01*
G02Y216471I1649J2203D01*
G03Y218073I-599J801D01*
G02X43579I1649J2203D01*
G03Y216471I599J-801D01*
G02Y212065I-1649J-2203D01*
G03Y210463I599J-801D01*
G02Y206057I-1649J-2203D01*
G03Y204456I600J-801D01*
G02Y200050I-1649J-2203D01*
G03Y198448I599J-801D01*
G02Y194042I-1649J-2203D01*
G03Y192440I599J-801D01*
G02Y188034I-1649J-2203D01*
G03Y186432I599J-801D01*
G02Y182026I-1649J-2203D01*
G03Y180424I599J-801D01*
G37*
G36*
G01X91358Y419624D02*
G02X88994Y419465I-1120J-1001D01*
G03X88911Y420692I-828J560D01*
G02X91275Y420851I1120J1001D01*
G03X91358Y419624I828J-560D01*
G37*
G36*
G01X99637Y419780D02*
G02X97267Y419734I-1167J-946D01*
G03X97243Y420962I-801J599D01*
G02X99613Y421008I1167J946D01*
G03X99637Y419780I801J-599D01*
G37*
G36*
G01X87091Y426194D02*
G02X85009I-1041J-1082D01*
G03Y427636I-694J721D01*
G02X87091I1041J1082D01*
G03Y426194I694J-721D01*
G37*
G36*
G01X102806Y426510D02*
G02X100494I-1156J-958D01*
G03Y427787I-770J638D01*
G02X102806I1156J958D01*
G03Y426510I770J-638D01*
G37*
G36*
G01X102795Y444010D02*
G02X100469Y443966I-1145J-972D01*
G03X100445Y445231I-786J618D01*
G02X102771Y445275I1145J972D01*
G03X102795Y444010I786J-618D01*
G37*
G36*
G01X119171Y452896D02*
G02X116813Y452926I-1191J-915D01*
G03X116829Y454164I-777J629D01*
G02X119187Y454134I1191J915D01*
G03X119171Y452896I777J-629D01*
G37*
G36*
G01X125062Y458646D02*
G02X123024Y458640I-1022J1100D01*
G03X121841Y458765I-676J-737D01*
G02X122096Y461166I-761J1295D01*
G03X123279Y461041I676J737D01*
G02X124831Y461023I761J-1295D01*
G03X126038Y461140I527J850D01*
G02X126269Y458763I1022J-1100D01*
G03X125062Y458646I-527J-850D01*
G37*
G36*
G01X127406Y467833D02*
G02X125278Y467762I-1029J-1095D01*
G03X125231Y469172I-732J681D01*
G02X127359Y469243I1029J1095D01*
G03X127406Y467833I732J-681D01*
G37*
G36*
G01X62559Y478792D02*
G02X60155I-1202J-900D01*
G03Y479992I-800J600D01*
G02X60184Y481830I1202J900D01*
G03Y482454I-391J312D01*
G02X60306Y484465I1173J938D01*
G03X60238Y485954I-700J714D01*
G02X60015Y488055I950J1163D01*
G03Y488679I-391J312D01*
G02Y490555I1173J938D01*
G03Y491179I-391J312D01*
G02X62361I1173J938D01*
G03Y490555I391J-312D01*
G02Y488679I-1173J-938D01*
G03Y488055I391J-312D01*
G02X62239Y486044I-1173J-938D01*
G03X62307Y484555I700J-714D01*
G02X62530Y482454I-950J-1163D01*
G03Y481830I391J-312D01*
G02X62559Y479992I-1173J-938D01*
G03Y478792I800J-600D01*
G37*
G36*
G01X117006Y485885D02*
G02X114932Y487080I-1490J-189D01*
G03X115536Y488127I-388J922D01*
G02X117313Y489790I1490J189D01*
G03X117887Y490137I95J491D01*
G02X120633Y490446I1439J-431D01*
G03X121689Y489957I870J493D01*
G02X120661Y487741I279J-1476D01*
G03X119605Y488230I-870J-493D01*
G02X119039Y488232I-278J1476D01*
G03X118465Y487885I-95J-491D01*
G02X117610Y486932I-1439J431D01*
G03X117006Y485885I388J-922D01*
G37*
G36*
G01X124291Y396828D02*
G03X123667I-312J-391D01*
G02Y399174I-938J1173D01*
G03X124291I312J391D01*
G02X126167I938J-1173D01*
G03X126791I312J391D01*
G02Y396828I938J-1173D01*
G03X126167I-312J-391D01*
G02X124291I-938J1173D01*
G37*
G36*
G01X112391Y405928D02*
G03X112414Y406639I-339J367D01*
G02X114952Y408073I1090J1034D01*
G03X115840Y407342I964J266D01*
G02X115327Y404396I-114J-1498D01*
G03X114749Y404142I-133J-482D01*
G02X112391Y405928I-1337J684D01*
G37*
G36*
G01X124788Y412752D02*
G03X124164I-312J-391D01*
G02Y415098I-938J1173D01*
G03X124788I312J391D01*
G02X126664I938J-1173D01*
G03X127288I312J391D01*
G02Y412752I938J-1173D01*
G03X126664I-312J-391D01*
G02X124788I-938J1173D01*
G37*
G36*
G01X115409Y417010D02*
G03Y415810I800J-600D01*
G02X113005I-1202J-900D01*
G03Y417010I-800J600D01*
G02X115409I1202J900D01*
G37*
G36*
G01X81692Y422790D02*
G03Y421590I800J-600D01*
G02X79288I-1202J-900D01*
G03Y422790I-800J600D01*
G02Y424590I1202J900D01*
G03Y425790I-800J600D01*
G02X81692I1202J900D01*
G03Y424590I800J-600D01*
G02Y422790I-1202J-900D01*
G37*
G36*
G01X102731Y435033D02*
G03Y434338I360J-347D01*
G02X100569I-1081J-1042D01*
G03Y435033I-360J347D01*
G02X102731I1081J1042D01*
G37*
G36*
G01X87252Y436570D02*
G03Y435370I800J-600D01*
G02X84848I-1202J-900D01*
G03Y436570I-800J600D01*
G02X87252I1202J900D01*
G37*
G36*
G01X81102Y441293D02*
G03Y440093I800J-600D01*
G02X78698I-1202J-900D01*
G03Y441293I-800J600D01*
G02Y443093I1202J900D01*
G03Y444293I-800J600D01*
G02X81102I1202J900D01*
G03Y443093I800J-600D01*
G02Y441293I-1202J-900D01*
G37*
G36*
G01X87252Y445532D02*
G03Y444332I800J-600D01*
G02X84848I-1202J-900D01*
G03Y445532I-800J600D01*
G02X87252I1202J900D01*
G37*
G36*
G01X66668Y449827D02*
G03X65468I-600J-800D01*
G02Y452231I-900J1202D01*
G03X66668I600J800D01*
G02X68468I900J-1202D01*
G03X69668I600J800D01*
G02Y449827I900J-1202D01*
G03X68468I-600J-800D01*
G02X66668I-900J1202D01*
G37*
G36*
G01X84717Y450073D02*
G03X83517I-600J-800D01*
G02Y452477I-900J1202D01*
G03X84717I600J800D01*
G02X86517I900J-1202D01*
G03X87717I600J800D01*
G02Y450073I900J-1202D01*
G03X86517I-600J-800D01*
G02X84717I-900J1202D01*
G37*
G36*
G01X63348Y464361D02*
G03X62203Y464211I-466J-884D01*
G02X61885Y466642I-1020J1103D01*
G03X63030Y466792I466J884D01*
G02X64800Y466991I1020J-1103D01*
G03X65473Y467159I249J433D01*
G02X65997Y465061I1274J-796D01*
G03X65324Y464893I-249J-433D01*
G02X63348Y464361I-1274J796D01*
G37*
G36*
G01X120386Y470884D02*
G03X119727Y470875I-324J-380D01*
G02X119694Y473133I-1007J1115D01*
G03X120353Y473142I324J380D01*
G02X120386Y470884I1007J-1115D01*
G37*
G36*
G01X105587Y263445D02*
G02X103345Y263255I-1037J-1086D01*
G03X103233Y264576I-802J597D01*
G02X105475Y264766I1037J1086D01*
G03X105587Y263445I802J-597D01*
G37*
G36*
G01X105024Y168673D02*
G02X104855Y166761I1066J-1058D01*
G03X103323Y166897I-823J-569D01*
G02X103492Y168809I-1066J1058D01*
G03X105024Y168673I823J569D01*
G37*
G36*
G01X126017Y92566D02*
G02X124144Y91850I-537J-1403D01*
G03X123613Y93240I-889J457D01*
G02X125486Y93956I537J1403D01*
G03X126017Y92566I889J-457D01*
G37*
G36*
G01X156109Y543276D02*
G02X153850Y543359I-1164J-893D01*
G03X153896Y544633I-747J665D01*
G02X156155Y544550I1164J893D01*
G03X156109Y543276I747J-665D01*
G37*
G36*
G01X485339Y561214D02*
G02X484068Y562632I-1501J-66D01*
G03X485219Y563664I152J988D01*
G02X485218Y563725I1501J55D01*
G03X484066Y564709I-1000J-4D01*
G02X485340Y566199I-228J1485D01*
G03X486492Y565215I1000J4D01*
G02X487794Y564780I228J-1485D01*
G03X489080Y564658I715J699D01*
G02X488864Y562375I858J-1233D01*
G03X487578Y562497I-715J-699D01*
G02X486490Y562246I-857J1233D01*
G03X485339Y561214I-152J-988D01*
G37*
G36*
G01X483880Y572695D02*
G02X482338Y571115I-42J-1501D01*
G03X481368Y572062I-999J-53D01*
G02X482910Y573642I42J1501D01*
G03X483880Y572695I999J53D01*
G37*
G36*
G01X191168Y573421D02*
G02X190123Y571355I332J-1465D01*
G03X188986Y571930I-916J-400D01*
G02X190031Y573996I-332J1465D01*
G03X191168Y573421I916J400D01*
G37*
G36*
G01X144725Y573399D02*
G02X142840Y574550I-1473J-294D01*
G03X143547Y575707I-274J962D01*
G02X145432Y574556I1473J294D01*
G03X144725Y573399I274J-962D01*
G37*
G36*
G01X223131Y579554D02*
G02X221959Y577931I322J-1467D01*
G03X220750Y578804I-995J-104D01*
G02X221922Y580427I-322J1467D01*
G03X223131Y579554I995J104D01*
G37*
G36*
G01X228596Y581047D02*
G02X227230Y582412I-1496J-131D01*
G03X228313Y583496I87J996D01*
G02X229679Y582131I1496J131D01*
G03X228596Y581047I-87J-996D01*
G37*
G36*
G01X251522Y583542D02*
G02X250678Y581489I514J-1411D01*
G03X250055Y581745I-452J-214D01*
G02X248639Y584357I-514J1411D01*
G03Y585955I-601J799D01*
G02X250443I902J1201D01*
G03Y584357I601J-799D01*
G02X250899Y583798I-902J-1201D01*
G03X251522Y583542I452J214D01*
G37*
G36*
G01X486873Y588109D02*
G02X484694Y588205I-1135J-984D01*
G03X484755Y589579I-695J719D01*
G02X486853Y591716I1134J985D01*
G03X488248Y591826I641J767D01*
G02X490652Y590040I1132J-987D01*
G03X491195Y588556I847J-531D01*
G02X489466Y587924I-457J-1431D01*
G03X488923Y589408I-847J531D01*
G02X488417Y589686I457J1431D01*
G03X487022Y589576I-641J-767D01*
G02X486934Y589483I-1134J985D01*
G03X486873Y588109I695J-719D01*
G37*
G36*
G01X270902Y587889D02*
G02X270640Y589746I-1293J765D01*
G03X272187Y589965I686J727D01*
G02X272449Y588108I1293J-765D01*
G03X270902Y587889I-686J-727D01*
G37*
G36*
G01X240422Y596166D02*
G02X240253Y598262I-1153J962D01*
G03X241677Y598377I656J756D01*
G02X241846Y596281I1153J-962D01*
G03X240422Y596166I-656J-756D01*
G37*
G36*
G01X499277Y570488D02*
G03X499327Y571137I-354J354D01*
G02X501599Y570962I1211J888D01*
G03X501549Y570313I354J-354D01*
G02X501540Y568525I-1211J-888D01*
G03Y567325I800J-600D01*
G02X499136I-1202J-900D01*
G03Y568525I-800J600D01*
G02X499277Y570488I1202J900D01*
G37*
G36*
G01X491858Y569822D02*
G03X491796Y568645I776J-631D01*
G02X489373Y568773I-1258J-820D01*
G03X489435Y569950I-776J631D01*
G02X491858Y569822I1258J820D01*
G37*
G36*
G01X241945Y574829D02*
G03X241871Y575459I-421J270D01*
G02X244309Y577099I1044J1080D01*
G03X245486Y576504I928J373D01*
G02X245249Y573677I374J-1455D01*
G03X244587Y573420I-204J-457D01*
G02X241945Y574829I-1378J598D01*
G37*
G36*
G01X400047Y585974D02*
G03X399371Y585992I-348J-359D01*
G02X399430Y588206I-985J1134D01*
G03X400106Y588188I348J359D01*
G02X400047Y585974I985J-1134D01*
G37*
G36*
G01X292208Y592113D02*
G03Y591463I380J-325D01*
G02X289924I-1142J-975D01*
G03Y592113I-380J325D01*
G02X292208I1142J975D01*
G37*
G36*
G01X384486Y592287D02*
G03Y591637I380J-325D01*
G02X382202I-1142J-975D01*
G03Y592287I-380J325D01*
G02X384486I1142J975D01*
G37*
G36*
G01X469708Y594207D02*
G03X469188Y595252I-987J161D01*
G02X471372Y596337I702J1328D01*
G03X471892Y595292I987J-161D01*
G02X469708Y594207I-702J-1328D01*
G37*
G36*
G01X312252Y589090D02*
G03X311602I-325J-380D01*
G02X309747Y591449I-975J1142D01*
G03X309864Y592971I-586J811D01*
G02X311857Y595213I1055J1069D01*
G01X311994Y595104D01*
X312344D01*
X312481Y595213D01*
G02X314331Y595233I938J-1173D01*
G03X314652Y595131I303J398D01*
G03X314965Y595255I-17J500D01*
G02X315045Y592934I992J-1128D01*
G03X314724Y593036I-303J-398D01*
G03X314411Y592912I17J-500D01*
G02X314333Y592848I-991J1129D01*
G03X314256Y591326I608J-794D01*
G02X312252Y589090I-1029J-1094D01*
G37*
G36*
G01X161545Y335540D02*
G03X160431Y335250I-351J-937D01*
G02X158258Y335124I-1146J970D01*
G03X157124Y335288I-684J-729D01*
G02X157475Y337725I-676J1341D01*
G03X158609Y337561I684J729D01*
G02X159811Y337627I676J-1341D01*
G03X160925Y337917I351J937D01*
G02X161545Y335540I1146J-970D01*
G37*
G36*
G01X215281Y385962D02*
G02X213202Y386432I-1273J-797D01*
G03X213513Y387806I-537J844D01*
G02X215592Y387336I1273J797D01*
G03X215281Y385962I537J-844D01*
G37*
G36*
G01X224913Y385762D02*
G02X222537Y386207I-1352J-654D01*
G03X222756Y387375I-681J732D01*
G02X222608Y388107I1352J654D01*
G03X221541Y389157I-999J52D01*
G02X220355Y389615I-103J1498D01*
G03X219017Y389709I-721J-693D01*
G02X219173Y391931I-927J1182D01*
G03X220511Y391837I721J693D01*
G02X222938Y390577I927J-1182D01*
G03X224005Y389527I999J-52D01*
G02X225132Y386930I103J-1498D01*
G03X224913Y385762I681J-732D01*
G37*
G36*
G01X163089Y325441D02*
G02X161341Y325730I-1072J-1052D01*
G03X161352Y326617I-226J446D01*
G02X161091Y326795I711J1323D01*
G03X160467Y326813I-323J-382D01*
G02X160536Y329158I-903J1200D01*
G03X161160Y329140I323J382D01*
G02X163107Y326860I903J-1200D01*
G03X163089Y325441I696J-718D01*
G37*
G36*
G01X211028Y500444D02*
G03X209961Y500025I-234J-972D01*
G02X209061Y502316I-1251J831D01*
G03X210128Y502735I234J972D01*
G02X211028Y500444I1251J-831D01*
G37*
G36*
G01X160095Y520878D02*
G02X160086Y522916I-916J1015D01*
G03X161419Y522921I664J748D01*
G02X161428Y520883I916J-1015D01*
G03X160095Y520878I-664J-748D01*
G37*
G36*
G01X170663Y518284D02*
G02X170210Y520486I-1048J932D01*
G03X171368Y520712I424J905D01*
G02X171816Y518534I1003J-929D01*
G03X170663Y518284I-405J-914D01*
G37*
G36*
G01X155128Y508723D02*
G02X153326Y508598I-821J-1216D01*
G03X153217Y510170I-669J743D01*
G02X153131Y512539I821J1216D01*
G03X153253Y513186I-309J393D01*
G02X153278Y514717I1264J745D01*
G03X153055Y516037I-844J536D01*
G02X152882Y518173I912J1149D01*
G03X152786Y519612I-739J673D01*
G02X152866Y521919I945J1122D01*
G03X153015Y523400I-590J807D01*
G02X154996Y523187I1111J1011D01*
G03X154828Y521708I580J-815D01*
G02X154816Y519747I-1097J-974D01*
G03X154912Y518308I739J-673D01*
G02X155206Y516400I-945J-1122D01*
G03X155429Y515080I844J-536D01*
G02X155424Y512778I-912J-1149D01*
G03X155302Y512131I309J-393D01*
G02X155019Y510295I-1264J-745D01*
G03X155128Y508723I669J-743D01*
G37*
G36*
G01X204095Y286231D02*
G02X201982Y288344I-946J1167D01*
G03Y289602I-777J629D01*
G02X204095Y291715I1167J946D01*
G03X205353I629J777D01*
G02X205372Y291730I940J-1172D01*
G03Y292516I-309J393D01*
G02X205142Y294655I927J1182D01*
G03X205150Y295920I-771J637D01*
G02X207476Y295906I1169J943D01*
G03X207468Y294641I771J-637D01*
G02X207466Y292752I-1169J-943D01*
G03Y291494I777J-629D01*
G02X207481Y291475I-1172J-940D01*
G03X208267I393J309D01*
G02X210395Y291715I1182J-927D01*
G03X211653I629J777D01*
G02X211672Y291730I940J-1172D01*
G03Y292516I-309J393D01*
G02X213766Y292752I927J1182D01*
G03Y291494I777J-629D01*
G02X213781Y291475I-1172J-940D01*
G03X214567I393J309D01*
G02X214803Y289381I1182J-927D01*
G03X213545I-629J-777D01*
G02X213526Y289366I-940J1172D01*
G03Y288580I309J-393D01*
G02X211653Y286231I-927J-1182D01*
G03X210395I-629J-777D01*
G02X208503I-946J1167D01*
G03X207245I-629J-777D01*
G02X205353I-946J1167D01*
G03X204095I-629J-777D01*
G37*
G36*
G01X213766Y300944D02*
G02X211432I-1167J-946D01*
G03Y302202I-777J629D01*
G02X211437Y304100I1167J946D01*
G03X211441Y305361I-774J633D01*
G02X213772Y305353I1169J944D01*
G03X213768Y304092I774J-633D01*
G02X213766Y302202I-1169J-944D01*
G03Y300944I777J-629D01*
G37*
G36*
G01X207466Y304094D02*
G02X205132I-1167J-946D01*
G03Y305352I-777J629D01*
G02X207466I1167J946D01*
G03Y304094I777J-629D01*
G37*
G36*
G01X195912Y307417D02*
G03X194712I-600J-800D01*
G02X193395Y310062I-900J1202D01*
G03X193755Y310572I-139J480D01*
G02X196460Y311558I1499J91D01*
G03X197909Y311391I803J596D01*
G02X198804Y308745I971J-1146D01*
G03X198288Y308339I-25J-499D01*
G02X195912Y307417I-1476J280D01*
G37*
G36*
G01X321981Y557305D02*
G03Y557929I-391J312D01*
G02X321999Y559828I1173J938D01*
G03X321983Y560486I-384J320D01*
G02X321917Y562444I1105J1017D01*
G03X321957Y563643I-780J626D01*
G02X324359Y563562I1231J860D01*
G03X324319Y562363I780J-626D01*
G02X324243Y560542I-1231J-861D01*
G03X324259Y559884I384J-320D01*
G02X324327Y557929I-1105J-1017D01*
G03Y557305I391J-312D01*
G02Y555429I-1173J-938D01*
G03Y554805I391J-312D01*
G02X321981I-1173J-938D01*
G03Y555429I-391J312D01*
G02Y557305I1173J938D01*
G37*
G36*
G01X256802Y553920D02*
G02X254544I-1129J-936D01*
G03Y555197I-770J638D01*
G02Y557069I1129J936D01*
G03Y558346I-770J638D01*
G02X254456Y558464I1130J935D01*
G03X253642Y558487I-415J-279D01*
G02X253421Y560371I-1088J827D01*
G03X254711Y560389I634J773D01*
G02X254794Y560456I962J-1107D01*
G03Y561257I-300J400D01*
G02X254544Y563367I879J1174D01*
G03Y564644I-770J638D01*
G02X256802I1129J936D01*
G03Y563367I770J-638D01*
G02Y561495I-1129J-936D01*
G03Y560218I770J-639D01*
G02Y558346I-1129J-936D01*
G03Y557069I770J-639D01*
G02Y555197I-1129J-936D01*
G03Y553920I770J-639D01*
G37*
G36*
G01X314337Y551729D02*
G02X311905Y551674I-1196J-908D01*
G03X311879Y552847I-823J569D01*
G02X312014Y554818I1196J908D01*
G03X312022Y555518I-353J354D01*
G02X311967Y557532I1086J1037D01*
G03X312033Y558745I-760J650D01*
G02X314416Y558614I1242J845D01*
G03X314350Y557401I760J-650D01*
G02X314169Y555493I-1242J-845D01*
G03X314161Y554793I353J-354D01*
G02X314311Y552902I-1086J-1038D01*
G03X314337Y551729I823J-569D01*
G37*
G36*
G01X281674Y550948D02*
G02X279814Y550706I-802J-1107D01*
G03X279783Y552008I-774J633D01*
G02X279700Y552110I1095J976D01*
G03X278899I-401J-300D01*
G02X276789Y551860I-1174J879D01*
G03X275510Y551858I-638J-770D01*
G02X273589Y551895I-939J1127D01*
G03X272286Y551927I-670J-742D01*
G02X270363Y553850I-865J1058D01*
G03X270331Y555153I-774J633D01*
G02X270294Y557074I1090J982D01*
G03Y558353I-769J640D01*
G02X270247Y558412I1124J943D01*
G03X269447I-400J-299D01*
G02X269209Y560420I-1175J879D01*
G03X270485I638J770D01*
G02X270540Y560463I931J-1134D01*
G03Y561262I-301J399D01*
G02X270293Y563370I882J1172D01*
G03Y564647I-770J638D01*
G02X272551I1129J936D01*
G03Y563370I770J-639D01*
G02X272553Y561500I-1129J-936D01*
G03Y560225I771J-638D01*
G02X272549Y558352I-1131J-934D01*
G03Y557073I769J-640D01*
G02X272640Y556952I-1126J-941D01*
G03X273461Y556939I415J278D01*
G02X275441Y557198I1111J-797D01*
G03X276744Y557226I635J772D01*
G02X276848Y557311I979J-1092D01*
G03Y558113I-299J401D01*
G02X278661Y560418I877J1176D01*
G03X279938I638J770D01*
G02X279995Y560463I937J-1128D01*
G03Y561264I-300J401D01*
G02X281811Y563567I879J1174D01*
G03X283087I638J770D01*
G02X283145Y563613I940J-1126D01*
G03Y564413I-299J400D01*
G02X284961Y566717I879J1175D01*
G03X286237I638J770D01*
G02X288110Y566718I937J-1129D01*
G03X289386I638J770D01*
G02X291260I937J-1129D01*
G03X292536I638J770D01*
G02X294602Y564652I937J-1129D01*
G03Y563376I770J-638D01*
G02Y561503I-1129J-936D01*
G03Y560226I770J-638D01*
G02X292537Y558161I-1129J-936D01*
G03X291260Y558160I-638J-770D01*
G02X291202Y558115I-928J1136D01*
G03Y557314I300J-400D01*
G02X289387Y555010I-879J-1175D01*
G03X288111I-638J-770D01*
G02X288053Y554964I-940J1126D01*
G03Y554164I299J-400D01*
G02X286237Y551860I-879J-1175D01*
G03X284961I-638J-770D01*
G02X283087I-937J1129D01*
G03X281811I-638J-770D01*
G02X281689Y551769I-937J1129D01*
G03X281674Y550948I278J-416D01*
G37*
G36*
G01X262909Y548707D02*
G02X260843Y550773I-937J1129D01*
G03Y552049I-770J638D01*
G02X260859Y553940I1130J936D01*
G03X260874Y555224I-759J651D01*
G02X263123Y555198I1135J929D01*
G03X263108Y553914I759J-651D01*
G02X263147Y553864I-1137J-927D01*
G03X263948I401J300D01*
G02X266251Y552049I1174J-879D01*
G03Y550772I770J-638D01*
G02X264185Y548707I-1130J-936D01*
G03X262909I-638J-770D01*
G37*
G36*
G01X327511Y546656D02*
G02X327137Y544529I841J-1244D01*
G03X325768Y544769I-809J-588D01*
G02X326142Y546896I-841J1244D01*
G03X327511Y546656I809J588D01*
G37*
G36*
G01X319878Y540062D02*
G02X319369Y542299I-1200J903D01*
G03X320628Y542586I460J888D01*
G02X323018Y542598I1200J-904D01*
G03X324521Y542504I793J610D01*
G02X326609Y542549I1067J-1057D01*
G03X327810Y542428I680J733D01*
G02X327571Y540044I782J-1282D01*
G03X326370Y540165I-680J-733D01*
G02X324398Y540531I-782J1282D01*
G03X322895Y540625I-793J-610D01*
G02X321137Y540349I-1067J1057D01*
G03X319878Y540062I-460J-888D01*
G37*
G36*
G01X288110Y539262D02*
G02X286045Y541328I-936J1130D01*
G03Y542604I-770J638D01*
G02X285999Y542662I1126J940D01*
G03X285199I-400J-299D01*
G02X283087Y542412I-1175J879D01*
G03X281811I-638J-770D01*
G02Y544670I-937J1129D01*
G03X283087I638J770D01*
G02X284961I937J-1129D01*
G03X286237I638J770D01*
G02X288110I937J-1129D01*
G03X289387I639J770D01*
G02X291452Y542604I936J-1130D01*
G03Y541328I770J-638D01*
G02X291498Y541270I-1126J-940D01*
G03X292298I400J299D01*
G02X292536Y539262I1175J-879D01*
G03X291260I-638J-770D01*
G02X289387I-936J1129D01*
G03X288110I-638J-770D01*
G37*
G36*
G01X281811Y532963D02*
G02X279745Y535028I-936J1129D01*
G03Y536305I-770J639D01*
G02X282003I1129J936D01*
G03Y535028I770J-638D01*
G02X282049Y534971I-1118J-949D01*
G03X282849I400J299D01*
G02X284961Y535221I1175J-879D01*
G03X286237I638J770D01*
G02X288110I937J-1129D01*
G03X289387I639J770D01*
G02X291260I936J-1129D01*
G03X292536I638J770D01*
G02Y532963I937J-1129D01*
G03X291260I-638J-770D01*
G02X289387I-936J1129D01*
G03X288110I-638J-770D01*
G02X286237I-936J1129D01*
G03X284961I-638J-770D01*
G02X283087I-937J1129D01*
G03X281811I-638J-770D01*
G37*
G36*
G01X262909Y532959D02*
G02X260843Y535024I-936J1129D01*
G03Y536301I-770J638D01*
G02Y538174I1129J936D01*
G03Y539450I-770J638D01*
G02X262909Y541516I1129J937D01*
G03X264185I638J770D01*
G02X266059I937J-1129D01*
G03X267335I638J770D01*
G02X269401Y539450I937J-1129D01*
G03Y538174I770J-638D01*
G02Y536301I-1129J-936D01*
G03Y535024I770J-638D01*
G02X267335Y532959I-1130J-936D01*
G03X266059I-638J-770D01*
G02X264185I-937J1129D01*
G03X262909I-638J-770D01*
G37*
G36*
G01X250311D02*
G02X248245Y535024I-936J1129D01*
G03Y536301I-770J638D01*
G02Y538174I1129J936D01*
G03Y539450I-770J638D01*
G02X250311Y541516I1129J937D01*
G03X251587I638J770D01*
G02X253460I937J-1129D01*
G03X254737I639J770D01*
G02X256802Y539450I936J-1130D01*
G03Y538174I770J-638D01*
G02Y536301I-1129J-936D01*
G03Y535024I770J-638D01*
G02X254737Y532959I-1129J-936D01*
G03X253460I-638J-770D01*
G02X251587I-936J1129D01*
G03X250311I-638J-770D01*
G37*
G36*
G01Y523510D02*
G02X248245Y525576I-937J1129D01*
G03Y526852I-770J638D01*
G02X250311Y528918I1129J937D01*
G03X251587I638J770D01*
G02X253460I937J-1129D01*
G03X254737I639J770D01*
G02X256802Y526852I936J-1130D01*
G03Y525576I770J-638D01*
G02X254737Y523510I-1129J-936D01*
G03X253460I-638J-770D01*
G02X251587I-936J1129D01*
G03X250311I-638J-770D01*
G37*
G36*
G01X262909Y520360D02*
G02X260843Y522426I-937J1129D01*
G03Y523702I-770J638D01*
G02Y525576I1129J937D01*
G03Y526852I-770J638D01*
G02X262909Y528918I1129J937D01*
G03X264185I638J770D01*
G02X266059I937J-1129D01*
G03X267335I638J770D01*
G02X269401Y526852I937J-1129D01*
G03Y525576I770J-638D01*
G02Y523702I-1129J-937D01*
G03Y522426I770J-638D01*
G02X267335Y520360I-1129J-937D01*
G03X266059I-638J-770D01*
G02X264185I-937J1129D01*
G03X262909I-638J-770D01*
G37*
G36*
G01X265937Y503811D02*
G02X264140Y501501I-816J-1220D01*
G03X262837Y501533I-670J-742D01*
G02X260952Y503501I-864J1059D01*
G03Y504831I-747J665D01*
G02Y506651I1020J910D01*
G03Y507981I-747J665D01*
G02X260913Y509756I1020J910D01*
G03X260882Y511058I-774J633D01*
G02X262909Y513169I1090J982D01*
G03X264185I638J770D01*
G02X266212Y511058I937J-1129D01*
G03X266180Y509756I742J-670D01*
G02X266230Y509690I-1064J-858D01*
G03X267052Y509705I406J292D01*
G02X269401Y507954I1221J-814D01*
G03Y506678I770J-638D01*
G02X267290Y504651I-1129J-937D01*
G03X265987Y504683I-670J-742D01*
G02X265922Y504632I-876J1049D01*
G03X265937Y503811I292J-405D01*
G37*
G36*
G01X272443Y497212D02*
G02X270400Y497195I-1014J-917D01*
G03X270388Y498524I-753J658D01*
G02X272431Y498541I1014J917D01*
G03X272443Y497212I753J-658D01*
G37*
G36*
G01X266632Y492621D02*
G02X266558Y490682I1109J-1013D01*
G03X265033Y490741I-787J-616D01*
G02X265107Y492680I-1109J1013D01*
G03X266632Y492621I787J616D01*
G37*
G36*
G01X224349Y478031D02*
G02X222403Y477223I-562J-1393D01*
G03X221856Y478540I-921J390D01*
G02X223802Y479348I562J1393D01*
G03X224349Y478031I921J-390D01*
G37*
G36*
G01X241876Y298030D02*
G02X239782Y297794I-927J-1182D01*
G03Y299052I-777J629D01*
G02X239768Y299070I1179J931D01*
G03X238981I-393J-309D01*
G02X236633Y300943I-1181J928D01*
G03X236632Y302202I-778J629D01*
G02X236617Y302221I1172J940D01*
G03X235831I-393J-309D01*
G02X235595Y304315I-1182J927D01*
G03X236853I629J777D01*
G02X236872Y304330I940J-1172D01*
G03Y305116I-309J393D01*
G02X238753Y307458I928J1181D01*
G03X240002Y307442I635J773D01*
G02X242109Y305333I923J-1185D01*
G03X242119Y304090I788J-615D01*
G02X242126Y304081I-1182J-927D01*
G03X242918Y304090I393J310D01*
G02X245304Y304108I1200J-903D01*
G03X246086Y304099I395J307D01*
G02X246322Y304330I1162J-951D01*
G03Y305116I-309J393D01*
G02X248416Y305352I927J1182D01*
G03Y304094I777J-629D01*
G02X246295Y301988I-1167J-946D01*
G03X245043Y302004I-636J-772D01*
G02X245019Y301985I-944J1168D01*
G03X245014Y301189I300J-400D01*
G02X243153Y298831I-915J-1191D01*
G03X241895I-629J-777D01*
G02X241876Y298816I-940J1172D01*
G03Y298030I309J-393D01*
G37*
G36*
G01X356879Y35852D02*
X356556D01*
G03X356056Y35352I1J-501D01*
G01Y35269D01*
G02X352660Y35258I-1709J3285D01*
G01Y35354D01*
G03X352160Y35854I-500J0D01*
G01X351814D01*
G02X351817Y41256I2534J2700D01*
G01X352162D01*
G03X352662Y41756I0J500D01*
G01Y41851D01*
G02X356056Y41839I1685J-3297D01*
G01Y41756D01*
G03X356556Y41256I501J1D01*
G01X356879D01*
G02X358051Y38554I-2531J-2703D01*
G02X356879Y35852I-3703J1D01*
G37*
G36*
G01X375297Y480362D02*
G02X372708Y479232I-1090J-1033D01*
G03X371458Y480135I-998J-65D01*
G02X371837Y482886I-378J1454D01*
G03X373085Y483082I504J864D01*
G02X375296Y481049I1118J-1003D01*
G03X375297Y480362I364J-343D01*
G37*
G36*
G01X375294Y496173D02*
G02X374020Y498077I-1444J412D01*
G03X375096Y498797I114J994D01*
G02X376370Y496893I1444J-412D01*
G03X375294Y496173I-114J-994D01*
G37*
G36*
G01X440376Y557213D02*
G02X440178Y555081I950J-1163D01*
G03X438782Y555211I-764J-645D01*
G02X438980Y557343I-950J1163D01*
G03X440376Y557213I764J645D01*
G37*
G36*
G01X452370Y527060D02*
G02X450388Y527155I-1045J-1079D01*
G03X450459Y528655I-624J781D01*
G02X452441Y528560I1045J1079D01*
G03X452370Y527060I624J-781D01*
G37*
G36*
G01X466786Y664657D02*
G03X466275Y665733I-981J193D01*
G02X468454Y666768I705J1326D01*
G03X468965Y665692I981J-193D01*
G02X466786Y664657I-705J-1326D01*
G37*
G36*
G01X446709Y666559D02*
G02X446026Y664219I501J-1416D01*
G03X444904Y664547I-789J-615D01*
G02X443314Y666998I-501J1416D01*
G03X443336Y668351I-725J688D01*
G02X445547Y668315I1122J999D01*
G03X445525Y666962I725J-688D01*
G02X445587Y666887I-1126J-994D01*
G03X446709Y666559I789J615D01*
G37*
G36*
G01X481805Y669350D02*
G02X481367Y667109I739J-1308D01*
G03X480092Y667358I-783J-622D01*
G02X480530Y669599I-739J1308D01*
G03X481805Y669350I783J622D01*
G37*
G36*
G01X413150Y672938D02*
G02X411575Y674153I-1475J-284D01*
G03X412491Y675340I-66J998D01*
G02X412474Y675794I1475J283D01*
G03X411348Y676898I-994J113D01*
G02X411240Y679886I-199J1489D01*
G03X412237Y680533I61J998D01*
G02X413552Y678505I1406J-529D01*
G03X412555Y677858I-61J-998D01*
G02X412384Y677533I-1405J532D01*
G03X413088Y676843I411J-285D01*
G02X414066Y674125I878J-1219D01*
G03X413150Y672938I66J-998D01*
G37*
G36*
G01X464827Y661834D02*
G03X464500Y661277I166J-472D01*
G02X462523Y662440I-1480J-254D01*
G03X462850Y662997I-166J472D01*
G02X464827Y661834I1480J254D01*
G37*
G36*
G01X458533Y663807D02*
G02X456650Y664672I-1395J-556D01*
G03X457255Y665987I-324J946D01*
G02X458334Y668011I1395J556D01*
G03X459108Y669163I-211J978D01*
G02X460903Y667956I1479J261D01*
G03X460129Y666804I211J-978D01*
G02X459138Y665122I-1479J-261D01*
G03X458533Y663807I324J-946D01*
G37*
G36*
G01X502468Y177764D02*
G02X499538Y177283I-1428J-466D01*
G03X498699Y178262I-1000J-8D01*
G02X500442Y179758I241J1482D01*
G03X501281Y178779I1000J8D01*
G02X501360Y178765I-222J-1485D01*
G03X501849Y179575I106J488D01*
G02X503251Y179060I1150J966D01*
G03X502468Y177764I167J-986D01*
G37*
G36*
G01X634943Y193519D02*
G03X633977Y192623I29J-1000D01*
G02X632792Y194251I-1494J158D01*
G03X633387Y194825I102J489D01*
G02X633360Y195119I1575J293D01*
G01Y199610D01*
G03X632410Y200577I-1000J-32D01*
G02X633934Y202473I75J1500D01*
G03X634923Y201737I965J264D01*
G02X635702Y201556I38J-1602D01*
G02X636564Y200121I-740J-1421D01*
G01Y200077D01*
X636566Y200074D01*
Y195059D01*
X636559Y194993D01*
G02X634943Y193519I-1597J128D01*
G37*
G36*
G01X625660Y178601D02*
G03X625472Y177097I554J-833D01*
G02X623500Y177323I-1114J-1007D01*
G03X623648Y178839I-571J821D01*
G02X623606Y178884I1150J1116D01*
G02X623198Y179951I1194J1068D01*
G01Y185029D01*
X623202Y185080D01*
G02X626402Y184953I1598J-113D01*
G01Y184909D01*
X626404Y184906D01*
Y179891D01*
X626397Y179825D01*
G02X625660Y178601I-1597J128D01*
G37*
G36*
G01X699148Y97697D02*
G02X678805I-10171J-12067D01*
G03X679494Y99177I-1246J1480D01*
G01Y105315D01*
G02X698460I9483J0D01*
G01Y99177D01*
G03X699148Y97697I1934J-1D01*
G37*
G36*
G01X608380Y193555D02*
X608350Y193782D01*
Y200932D01*
X608393Y201204D01*
G02X615053Y200690I3309J-532D01*
G02X615054Y200656I-3348J-115D01*
G01Y193991D01*
G02X608380Y193555I-3352J5D01*
G37*
G36*
G01Y178555D02*
X608350Y178782D01*
Y185932D01*
X608393Y186204D01*
G02X615053Y185690I3309J-532D01*
G02X615054Y185656I-3348J-115D01*
G01Y178991D01*
G02X608380Y178555I-3352J5D01*
G37*
G36*
G01X769545Y585003D02*
G03X769601Y586190I-775J631D01*
G02X772015Y586076I1249J835D01*
G03X771959Y584889I775J-631D01*
G02X769545Y585003I-1249J-835D01*
G37*
G36*
G01X769708Y576735D02*
G03X769812Y577888I-760J650D01*
G02X772252Y577668I1298J755D01*
G03X772148Y576515I760J-650D01*
G02X769708Y576735I-1298J-755D01*
G37*
G36*
G01X721358Y560183D02*
G03X722527Y560149I608J794D01*
G02X724377Y560020I843J-1243D01*
G03X725072Y560044I335J371D01*
G02X727126Y560147I1082J-1042D01*
G03X727752Y560130I324J381D01*
G02X729614Y560095I909J-1196D01*
G03X730261Y560105I318J386D01*
G02X730298Y557814I990J-1130D01*
G03X729651Y557804I-318J-386D01*
G02X727689Y557789I-990J1130D01*
G03X727063Y557806I-324J-381D01*
G02X725147Y557888I-909J1196D01*
G03X724452Y557864I-335J-371D01*
G02X722457Y557713I-1082J1042D01*
G03X721288Y557747I-608J-794D01*
G02X721358Y560183I-843J1243D01*
G37*
G36*
G01X754054Y336328D02*
G03X754216Y337012I-265J424D01*
G02X756296Y336518I1284J779D01*
G03X756134Y335834I265J-424D01*
G02X754054Y336328I-1284J-779D01*
G37*
G36*
G01X749170Y312272D02*
G03X749202Y313466I-786J618D01*
G02X751610Y313401I1228J864D01*
G03X751578Y312207I786J-618D01*
G02X749170Y312272I-1228J-864D01*
G37*
G36*
G01X513914Y206985D02*
G03X513223Y206862I-283J-412D01*
G02X512849Y208967I-1226J868D01*
G03X513540Y209090I283J412D01*
G02X513914Y206985I1226J-868D01*
G37*
G36*
G01X669386Y186905D02*
G03X668194I-596J-803D01*
G02Y189319I-894J1207D01*
G03X669386I596J803D01*
G02Y186905I894J-1207D01*
G37*
G36*
G01X689530Y118939D02*
G02X689470I-30J1502D01*
G03X689006Y118648I-10J-500D01*
G02X687188Y117484I-1818J838D01*
G01X685129D01*
X683518Y119095D01*
Y158365D01*
X685675Y160522D01*
X755485D01*
X758202Y157805D01*
Y118986D01*
G02X756700Y117484I-1502J0D01*
G01X691812D01*
G02X689994Y118648I0J2002D01*
G03X689530Y118939I-454J-209D01*
G37*
G36*
G01X748612Y583282D02*
G02X746314Y583289I-1152J-964D01*
G03X746318Y584578I-763J647D01*
G02X748616Y584571I1152J964D01*
G03X748612Y583282I763J-647D01*
G37*
G36*
G01X745209Y572790D02*
G02X742915Y572818I-1159J-956D01*
G03X742931Y574110I-755J655D01*
G02X743061Y576160I1159J956D01*
G03X743006Y577666I-685J729D01*
G02X744980Y577739I945J1167D01*
G03X745035Y576233I685J-729D01*
G02X745225Y574082I-945J-1167D01*
G03X745209Y572790I755J-655D01*
G37*
G36*
G01X692434Y560990D02*
G02X690630I-902J-1201D01*
G03Y562588I-601J799D01*
G02Y564990I902J1201D01*
G03Y566588I-601J799D01*
G02Y568990I902J1201D01*
G03Y570588I-601J799D01*
G02Y572990I902J1201D01*
G03Y574588I-601J799D01*
G02Y576990I902J1201D01*
G03Y578588I-601J799D01*
G02Y580990I902J1201D01*
G03Y582588I-601J799D01*
G02Y584990I902J1201D01*
G03Y586588I-601J799D01*
G02X692434I902J1201D01*
G03Y584990I601J-799D01*
G02Y582588I-902J-1201D01*
G03Y580990I601J-799D01*
G02Y578588I-902J-1201D01*
G03Y576990I601J-799D01*
G02Y574588I-902J-1201D01*
G03Y572990I601J-799D01*
G02Y570588I-902J-1201D01*
G03Y568990I601J-799D01*
G02Y566588I-902J-1201D01*
G03Y564990I601J-799D01*
G02Y562588I-902J-1201D01*
G03Y560990I601J-799D01*
G37*
G36*
G01X768124Y559255D02*
G02X765710Y559165I-1174J-937D01*
G03X765666Y560353I-826J564D01*
G02X765794Y562367I1174J936D01*
G03X765814Y563064I-349J359D01*
G02X765748Y565019I1106J1016D01*
G03X765740Y566279I-781J625D01*
G02X765750Y568199I1160J954D01*
G03X765730Y568864I-383J321D01*
G02X765636Y570822I1090J1034D01*
G03X765668Y572009I-788J615D01*
G02X768084Y571944I1232J860D01*
G03X768052Y570757I788J-615D01*
G02X767970Y568931I-1232J-860D01*
G03X767990Y568266I383J-321D01*
G02X768072Y566294I-1090J-1033D01*
G03X768080Y565034I781J-625D01*
G02X767966Y563003I-1160J-954D01*
G03X767946Y562306I349J-359D01*
G02X768080Y560443I-1106J-1016D01*
G03X768124Y559255I826J-564D01*
G37*
G36*
G01X688043Y540816D02*
G02X686075Y540599I-860J-1231D01*
G03X685910Y542094I-738J675D01*
G02X687878Y542311I860J1231D01*
G03X688043Y540816I738J-675D01*
G37*
G36*
G01X679148Y537931D02*
G02X677345Y537975I-931J-1179D01*
G03X677384Y539573I-581J814D01*
G02X679187Y539529I931J1179D01*
G03X679148Y537931I581J-814D01*
G37*
G36*
G01X734255Y489868D02*
G02X732434Y490887I-1438J-433D01*
G03X733137Y492142I-255J967D01*
G02X734958Y491123I1438J433D01*
G03X734255Y489868I255J-967D01*
G37*
G36*
G01X726918Y485869D02*
G02X726889Y487743I-1188J919D01*
G03X728452Y487767I772J636D01*
G02X728481Y485893I1188J-919D01*
G03X726918Y485869I-772J-636D01*
G37*
G36*
G01X766447Y358696D02*
G02X764269Y358926I-1197J-907D01*
G03X764413Y360287I-653J757D01*
G02X766591Y360057I1197J907D01*
G03X766447Y358696I653J-757D01*
G37*
G36*
G01X748623Y322427D02*
G02X748438Y324773I-1023J1100D01*
G03X749677Y324871I558J830D01*
G02X749862Y322525I1023J-1100D01*
G03X748623Y322427I-558J-830D01*
G37*
G36*
G01X656380Y228085D02*
G02X655824Y230019I-1350J659D01*
G03X657251Y230429I529J849D01*
G02X657807Y228495I1350J-659D01*
G03X656380Y228085I-529J-849D01*
G37*
G36*
G01X657820Y223908D02*
G02X657212Y221998I762J-1294D01*
G03X655792Y222450I-912J-410D01*
G02X656400Y224360I-762J1294D01*
G03X657820Y223908I912J410D01*
G37*
G36*
G01X594529Y221927D02*
G02X594484Y220123I1178J-932D01*
G03X592885Y220163I-815J-580D01*
G02X592930Y221967I-1178J932D01*
G03X594529Y221927I815J580D01*
G37*
G36*
G01X580930Y219790D02*
G02X580885Y221594I-1223J872D01*
G03X582484Y221634I784J620D01*
G02X584915Y221654I1223J-872D01*
G03X586514Y221641I804J594D01*
G02X586499Y219836I1193J-912D01*
G03X584900Y219849I-804J-594D01*
G02X582529Y219830I-1193J913D01*
G03X580930Y219790I-784J-620D01*
G37*
G36*
G01X666586Y214008D02*
G02X666553Y215866I-1196J908D01*
G03X668124Y215894I774J633D01*
G02X668157Y214036I1196J-908D01*
G03X666586Y214008I-774J-633D01*
G37*
G36*
G01X666516Y202339D02*
G02X666483Y204197I-1196J908D01*
G03X668054Y204225I774J633D01*
G02X668087Y202367I1196J-908D01*
G03X666516Y202339I-774J-633D01*
G37*
G36*
G01X665611Y192516D02*
G02X663509I-1051J-1073D01*
G03Y193945I-700J714D01*
G02X665611I1051J1073D01*
G03Y192516I700J-714D01*
G37*
G36*
G01X719047Y196022D02*
G02X704103I-7472J-667D01*
G03X703107Y197110I-996J88D01*
G01X676686D01*
X675158Y198638D01*
Y238881D01*
X677936Y241658D01*
X708875D01*
G03X709806Y243023I0J1000D01*
G02X716144I3169J1238D01*
G03X717075Y241658I931J-365D01*
G01X719175D01*
G03X720106Y243023I0J1000D01*
G02X726178Y242487I3169J1238D01*
G01X726087Y242339D01*
X726128Y241995D01*
X728372Y239752D01*
Y229509D01*
G03X729913Y228668I1000J0D01*
G02Y216054I4062J-6307D01*
G03X728372Y215213I-541J-841D01*
G01Y202503D01*
G03X729913Y201662I1000J0D01*
G02X726564Y196522I4062J-6307D01*
G03X724869Y197385I-988J156D01*
G01X724595Y197110D01*
X720043D01*
G03X719047Y196022I0J-1000D01*
G37*
G36*
G01X494968Y172627D02*
G02X492696Y173015I-1298J-756D01*
G03X492912Y174279I-648J761D01*
G02X495184Y173891I1298J756D01*
G03X494968Y172627I648J-761D01*
G37*
G36*
G01X657012Y163845D02*
G02X656338Y165925I-1317J722D01*
G03X657642Y166347I428J904D01*
G02X658316Y164267I1317J-722D01*
G03X657012Y163845I-428J-904D01*
G37*
G36*
G01X658366Y159711D02*
G02X657611Y157701I606J-1374D01*
G03X656301Y158193I-906J-423D01*
G02X657056Y160203I-606J1374D01*
G03X658366Y159711I906J423D01*
G37*
G36*
G01X656953Y149182D02*
G02X656207Y151307I-1311J733D01*
G03X657456Y151746I376J927D01*
G02X658202Y149621I1311J-733D01*
G03X656953Y149182I-376J-927D01*
G37*
G36*
G01X658251Y145040D02*
G02X657409Y142991I518J-1410D01*
G03X656160Y143505I-905J-425D01*
G02X657002Y145554I-518J1410D01*
G03X658251Y145040I905J425D01*
G37*
G36*
G01X595439Y139632D02*
G02X593936Y138164I-1J-1502D01*
G03X592937Y139187I-1000J23D01*
G02X594440Y140655I1J1502D01*
G03X595439Y139632I1000J-23D01*
G37*
G36*
G01X594440Y117692D02*
G02X592881Y119158I-1502J-35D01*
G03X593843Y120181I-38J999D01*
G02X594069Y121008I1502J34D01*
G03X593899Y122269I-850J527D01*
G02X596196Y122578I1021J1101D01*
G03X596366Y121317I850J-527D01*
G02X595402Y118715I-1021J-1101D01*
G03X594440Y117692I38J-999D01*
G37*
G36*
G01X547933Y107918D02*
G02X545997Y107413I-685J-1336D01*
G03X545621Y108857I-833J554D01*
G02X547557Y109362I685J1336D01*
G03X547933Y107918I833J-554D01*
G37*
G36*
G01X542106Y107828D02*
G02X540747Y106284I142J-1495D01*
G03X539652Y107247I-1000J-33D01*
G02X541011Y108791I-142J1495D01*
G03X542106Y107828I1000J33D01*
G37*
G36*
G01X739547Y106565D02*
G02X737735Y106551I-897J-1205D01*
G03X737723Y108146I-609J793D01*
G02X737463Y110309I897J1205D01*
G03Y111585I-770J638D01*
G02X739777I1157J958D01*
G03Y110309I770J-638D01*
G02X739535Y108160I-1157J-958D01*
G03X739547Y106565I609J-793D01*
G37*
G36*
G01X727087Y106530D02*
G02X725275Y106516I-897J-1205D01*
G03X725263Y108111I-609J793D01*
G02X725003Y110274I897J1205D01*
G03Y111550I-770J638D01*
G02X727317I1157J958D01*
G03Y110274I770J-638D01*
G02X727075Y108125I-1157J-958D01*
G03X727087Y106530I609J-793D01*
G37*
G36*
G01X763766Y104285D02*
G02X761470Y104256I-1136J-983D01*
G03X761454Y105546I-772J636D01*
G02X763750Y105575I1136J983D01*
G03X763766Y104285I772J-636D01*
G37*
G36*
G01X518181Y99465D02*
G02X515733Y99460I-1226J868D01*
G03X514134Y99498I-814J-582D01*
G02X514177Y101301I-1179J930D01*
G03X515776Y101263I814J582D01*
G02X518131Y101268I1179J-930D01*
G03X519729Y101312I782J622D01*
G02X519779Y99509I1226J-868D01*
G03X518181Y99465I-782J-622D01*
G37*
G36*
G01X625474Y82866D02*
G02X622999Y84344I-1454J377D01*
G03X622891Y85898I-680J733D01*
G02X622611Y88110I859J1232D01*
G03X622601Y89425I-758J652D01*
G02X622608Y91426I1124J997D01*
G03X622646Y92718I-744J668D01*
G02X622679Y94631I1174J937D01*
G03X622595Y96018I-760J650D01*
G02X623666Y98626I1015J1107D01*
G03X624693Y99486I37J999D01*
G02X627377Y98369I1487J-210D01*
G03X627433Y97093I797J-604D01*
G02X625912Y94638I-1113J-1009D01*
G03X625352Y93893I-135J-481D01*
G03X626193Y93421I849J528D01*
G02X627338Y90963I-13J-1502D01*
G03X627418Y89603I771J-637D01*
G02X627482Y87497I-1038J-1086D01*
G03Y86138I733J-680D01*
G02X626417Y83615I-1102J-1021D01*
G03X625474Y82866I25J-1000D01*
G37*
G36*
G01X611852Y66900D02*
G02X608614Y65176I-3238J2179D01*
G02X604612Y69178I0J4002D01*
G02X611831Y71402I3952J0D01*
G03X613389Y71283I827J563D01*
G02X613408Y67031I2268J-2116D01*
G03X611852Y66900I-726J-688D01*
G37*
G36*
G01X587194D02*
G02X583956Y65176I-3238J2179D01*
G02X579954Y69178I0J4002D01*
G02X587173Y71402I3952J0D01*
G03X588731Y71283I827J563D01*
G02X588750Y67031I2268J-2116D01*
G03X587194Y66900I-726J-688D01*
G37*
G36*
G01X677151Y52908D02*
G02X677105Y54711I-1224J871D01*
G03X678703Y54752I784J621D01*
G02X678749Y52949I1224J-871D01*
G03X677151Y52908I-784J-621D01*
G37*
G36*
G01X642793Y54637D02*
G02X642720Y52836I1164J-949D01*
G03X641121Y52900I-823J-567D01*
G02X641194Y54701I-1164J949D01*
G03X642793Y54637I823J567D01*
G37*
G36*
G01X657158Y52788D02*
G02X657137Y54593I-1211J889D01*
G03X658736Y54611I793J610D01*
G02X658757Y52806I1211J-889D01*
G03X657158Y52788I-793J-610D01*
G37*
G36*
G01X641352Y311037D02*
G02Y312893I-1181J928D01*
G03X642924I786J618D01*
G02Y311037I1181J-928D01*
G03X641352I-786J-618D01*
G37*
G36*
G01X655357Y316554D02*
G02X653711Y315584I-234J-1484D01*
G03X652927Y316914I-940J342D01*
G02X652262Y317196I237J1483D01*
G03X651062I-600J-800D01*
G02Y319600I-900J1202D01*
G03X652262I600J800D01*
G02X654573Y317884I900J-1202D01*
G03X655357Y316554I940J-342D01*
G37*
G36*
G01X653452Y322736D02*
G03X652252I-600J-800D01*
G02Y325140I-900J1202D01*
G03X653452I600J800D01*
G02Y322736I900J-1202D01*
G37*
G36*
G01X551222Y244856D02*
G02X548888Y244893I-1182J-927D01*
G03X548908Y246152I-767J642D01*
G02X551242Y246115I1182J927D01*
G03X551222Y244856I767J-642D01*
G37*
G36*
G01X593798Y248251D02*
G02X591928Y248258I-939J-1172D01*
G03X591934Y249823I-620J785D01*
G02X593804Y249816I939J1172D01*
G03X593798Y248251I620J-785D01*
G37*
G36*
G01X602045Y248854D02*
G02Y250736I-1171J941D01*
G03X603603I779J627D01*
G02X605825Y250868I1171J-941D01*
G03X607223I699J715D01*
G02Y248722I1051J-1073D01*
G03X605825I-699J-715D01*
G02X603603Y248854I-1051J1073D01*
G03X602045I-779J-627D01*
G37*
G36*
G01X596750Y270187D02*
G02X595078Y268824I-176J-1492D01*
G03X594198Y269903I-996J86D01*
G02X595870Y271266I176J1492D01*
G03X596750Y270187I996J-86D01*
G37*
G36*
G01X601845Y267854D02*
G02Y269736I-1171J941D01*
G03X603403I779J627D01*
G02X603458Y269801I1174J-938D01*
G03X603538Y271039I-742J670D01*
G02X605890Y270887I1236J854D01*
G03X605810Y269649I742J-670D01*
G02X605962Y269369I-1237J-853D01*
G03X606886I462J191D01*
G02X607163Y267784I1388J-574D01*
G03X605685I-739J-673D01*
G02X603403Y267854I-1111J1011D01*
G03X601845I-779J-627D01*
G37*
G36*
G01X531588Y279786D02*
G02X530256Y281597I-1469J315D01*
G03X531325Y282383I91J996D01*
G02X532657Y280572I1469J-315D01*
G03X531588Y279786I-91J-996D01*
G37*
G36*
G01X576917Y283476D02*
G02X574831I-1043J-1081D01*
G03Y284914I-695J719D01*
G02X574933Y287166I1043J1081D01*
G03Y288724I-627J779D01*
G02X576815I941J1171D01*
G03Y287166I627J-779D01*
G02X576917Y284914I-941J-1171D01*
G03Y283476I695J-719D01*
G37*
G36*
G01X558407Y284186D02*
G02X558224Y286228I-1185J923D01*
G03X559680Y286357I668J744D01*
G02X559863Y284315I1185J-923D01*
G03X558407Y284186I-668J-744D01*
G37*
G36*
G01X625220Y293838D02*
G02X623376Y293706I-837J-1247D01*
G03X623264Y295278I-670J742D01*
G02X625108Y295410I837J1247D01*
G03X625220Y293838I670J-742D01*
G37*
G36*
G01X672350Y303474D02*
G02X669959Y303445I-1184J-924D01*
G03X669945Y304655I-803J596D01*
G02X672336Y304684I1184J924D01*
G03X672350Y303474I803J-596D01*
G37*
G36*
G01X578141Y311262D02*
G02X576671Y312948I-1491J184D01*
G03X577677Y313825I14J1000D01*
G02X580659I1491J-184D01*
G03X581651Y312948I992J123D01*
G02X581824Y312938I0J-1502D01*
G03X582374Y313522I58J497D01*
G02X584030Y312291I1479J261D01*
G03X583149Y311357I117J-993D01*
G02X580159Y311262I-1499J89D01*
G03X579167Y312139I-992J-123D01*
G01X579147D01*
G03X578141Y311262I-14J-1000D01*
G37*
G36*
G01X592868Y263510D02*
G03X592916Y264203I-335J371D01*
G02X595073Y264053I1151J965D01*
G03X595025Y263360I335J-371D01*
G02X592868Y263510I-1151J-965D01*
G37*
G36*
G01X641272Y285996D02*
G03X641977Y285927I387J317D01*
G02X641772Y283814I955J-1159D01*
G03X641067Y283883I-387J-317D01*
G02X641272Y285996I-955J1159D01*
G37*
G36*
G01X639696Y295722D02*
G03X639891Y296384I-250J433D01*
G02X642093Y298297I1336J686D01*
G03X643246Y298298I576J818D01*
G02X644980Y295845I867J-1227D01*
G03X644604Y294730I578J-816D01*
G02X642092Y293236I-1434J-448D01*
G03X641413Y293271I-358J-349D01*
G02X639696Y295722I-965J1151D01*
G37*
G36*
G01X518019Y541613D02*
G03X518144Y542262I-306J395D01*
G02X520357Y541837I1294J763D01*
G03X520232Y541188I306J-395D01*
G02X518019Y541613I-1294J-763D01*
G37*
G36*
G01X529260Y540924D02*
G03X529884Y540824I373J333D01*
G02X529516Y538526I754J-1299D01*
G03X528892Y538626I-373J-333D01*
G02X527011Y538932I-754J1299D01*
G03X526312Y538982I-375J-331D01*
G02X526465Y541118I-974J1143D01*
G03X527164Y541068I375J331D01*
G02X529260Y540924I974J-1143D01*
G37*
G36*
G01X513321Y589675D02*
G02X513224Y592050I-967J1150D01*
G03X514446Y592100I579J815D01*
G02X514543Y589725I967J-1150D01*
G03X513321Y589675I-579J-815D01*
G37*
G36*
G01X552594Y569593D02*
G02X550302Y569378I-1056J-1068D01*
G03X550182Y570657I-823J568D01*
G02X552474Y570872I1056J1068D01*
G03X552594Y569593I823J-568D01*
G37*
G36*
G01X552133Y548293D02*
G02X550295Y548375I-972J-1145D01*
G03X550366Y549955I-576J817D01*
G02X552204Y549873I972J1145D01*
G03X552133Y548293I576J-817D01*
G37*
G36*
G01X542433Y538715D02*
G02X542385Y540595I-1195J910D01*
G03X543943Y540635I763J646D01*
G02X543991Y538755I1195J-910D01*
G03X542433Y538715I-763J-646D01*
G37*
G36*
G01X525172Y527869D02*
G02X524625Y530061I-1234J856D01*
G03X525904Y530381I457J889D01*
G02X528129Y530654I1234J-856D01*
G03X529447I659J752D01*
G02Y528396I991J-1129D01*
G03X528129I-659J-752D01*
G02X526451Y528189I-991J1129D01*
G03X525172Y527869I-457J-889D01*
G37*
G36*
G01X530453Y429993D02*
G02X527622Y429940I-1425J476D01*
G03X526588Y430582I-935J-353D01*
G02X527846Y432606I-148J1495D01*
G03X528880Y431964I935J353D01*
G02X529051Y431971I147J-1495D01*
G03X530015Y432654I16J1000D01*
G02X531417Y430676I1425J-476D01*
G03X530453Y429993I-16J-1000D01*
G37*
G36*
G01X531773Y420957D02*
G03X531361Y419866I554J-832D01*
G02X529077Y420728I-1451J-388D01*
G03X529489Y421819I-554J832D01*
G02X531773Y420957I1451J388D01*
G37*
G36*
G01X545509Y456117D02*
G03X544190Y455438I-353J-936D01*
G02X543267Y457229I-1452J385D01*
G03X544586Y457908I353J936D01*
G02X545509Y456117I1452J-385D01*
G37*
G36*
G01X678516Y403193D02*
G03X678096Y403703I-500J16D01*
G02X679839Y405135I242J1482D01*
G03X680259Y404625I500J-16D01*
G02X678516Y403193I-242J-1482D01*
G37*
G36*
G01X676899Y388288D02*
G03X676937Y388963I-349J358D01*
G02X679146Y388838I1162J952D01*
G03X679108Y388163I349J-358D01*
G02X676899Y388288I-1162J-952D01*
G37*
G36*
G01X680594Y351712D02*
G03X680554Y351009I335J-372D01*
G02X678426Y351130I-1124J-996D01*
G03X678466Y351833I-335J372D01*
G02X678099Y352648I1124J996D01*
G03X677106Y353528I-993J-120D01*
G01X654448D01*
Y365360D01*
X658136D01*
G03X658636Y365860I0J500D01*
G01Y365867D01*
G02X660949Y367149I1502J18D01*
G03X662346Y367474I541J841D01*
G02X665120Y366495I1286J-776D01*
G03X666111Y365360I991J-135D01*
G01X667313D01*
X667546Y365498D01*
X667613Y365617D01*
G02X670237I1312J-730D01*
G01X670304Y365498D01*
X670537Y365360D01*
X670773D01*
G03X671273Y365860I0J500D01*
G01Y365898D01*
X671267Y365935D01*
G02X674249Y366280I1485J226D01*
G03X675246Y365360I997J80D01*
G01X679132D01*
Y354831D01*
G03X679621Y354331I500J0D01*
G02X680594Y351712I-31J-1502D01*
G37*
G36*
G01X622834Y591174D02*
X622040Y591968D01*
Y613533D01*
X622834Y614326D01*
X644440D01*
X645398Y613368D01*
Y592092D01*
X644481Y591174D01*
X622834D01*
G37*
G36*
G01X650215Y416200D02*
G03X649555Y416159I-307J-395D01*
G02X649416Y418406I-1062J1062D01*
G03X650076Y418447I307J395D01*
G02X651989Y418623I1062J-1062D01*
G03X652616Y418672I283J412D01*
G02X652798Y416344I1033J-1090D01*
G03X652171Y416295I-283J-412D01*
G02X650215Y416200I-1033J1090D01*
G37*
G36*
G01X667515Y418642D02*
G03X668131Y418490I401J299D01*
G02X667576Y416235I648J-1355D01*
G03X666960Y416387I-401J-299D01*
G02X665213Y416718I-648J1355D01*
G03X664554Y416782I-366J-341D01*
G02X664773Y419023I-880J1217D01*
G03X665432Y418959I366J341D01*
G02X667515Y418642I880J-1217D01*
G37*
G36*
G01X631957Y409199D02*
G02X631209Y411417I-1266J808D01*
G03X632397Y411817I345J938D01*
G02X634582Y412197I1266J-808D01*
G03X635750Y412158I611J792D01*
G02X635667Y409722I836J-1248D01*
G03X634499Y409761I-611J-792D01*
G02X633145Y409599I-836J1248D01*
G03X631957Y409199I-345J-938D01*
G37*
G36*
G01X633212Y405159D02*
G02X632287Y403050I421J-1442D01*
G03X631112Y403565I-895J-445D01*
G02X632037Y405674I-421J1442D01*
G03X633212Y405159I895J445D01*
G37*
G36*
G01X636999Y387966D02*
G02X635492Y386578I-9J-1502D01*
G03X634502Y387654I-997J76D01*
G02X636009Y389042I9J1502D01*
G03X636999Y387966I997J-76D01*
G37*
G54D32*
X40749Y249194D03*
G54D30*
X49244Y360352D03*
X89810Y765905D03*
X19450Y550297D03*
X20650Y546243D03*
X20350Y555807D03*
X18960Y572061D03*
X17876Y578422D03*
X16200Y566921D03*
X21881Y595792D03*
X14500Y601957D03*
X11980Y617956D03*
X14550Y628297D03*
X13807Y634826D03*
X9300Y631472D03*
X9240Y638699D03*
X17071Y658951D03*
X38349Y555730D03*
X33231Y556346D03*
X30672Y551245D03*
X23610Y568111D03*
X34440Y597285D03*
X28112Y591718D03*
X36930Y611082D03*
X28270Y602194D03*
X33140Y602232D03*
X28185Y612088D03*
X35862Y617052D03*
X30744Y617898D03*
X29964Y658951D03*
X24168Y655750D03*
X37920Y651828D03*
X50870Y564008D03*
X43467Y555938D03*
X53988Y568748D03*
X49680Y579709D03*
X49620Y574212D03*
X47557Y588971D03*
X44507Y594082D03*
X40908Y589691D03*
X43850Y602797D03*
X42950Y612487D03*
X52230Y614907D03*
X47480Y616848D03*
X50170Y636895D03*
X51038Y643928D03*
X46890Y633564D03*
X53751Y652029D03*
X44640Y651029D03*
X40980Y656396D03*
X57710Y572918D03*
X57070Y580074D03*
X69766Y582525D03*
X57440Y585607D03*
X68630Y599945D03*
X63570Y613914D03*
X61600Y653611D03*
X66880Y761625D03*
X80630Y689682D03*
X82847Y716068D03*
X98410Y680541D03*
X100223Y733207D03*
X109640Y611890D03*
X109410Y621425D03*
X109500Y616724D03*
X109260Y644687D03*
Y648989D03*
X117790Y667235D03*
X115748Y716275D03*
X128240Y666583D03*
X132190Y662616D03*
X132050Y671817D03*
X130260Y679836D03*
X133490Y695470D03*
X126220Y720949D03*
X148140Y660112D03*
X148200Y669205D03*
X140110Y675907D03*
X143823Y682907D03*
X139158Y686725D03*
X138726Y696707D03*
X150840Y682436D03*
X149860Y726626D03*
X160320Y786346D03*
X178982Y688631D03*
X171180Y683815D03*
X169268Y705304D03*
X169619Y693335D03*
X180820Y717914D03*
X171154Y715673D03*
X169531Y710542D03*
X175463Y720245D03*
X177920Y739302D03*
X177224Y777765D03*
X167350Y778074D03*
X182163Y684555D03*
X185440Y712499D03*
X191930Y712624D03*
X194440Y735623D03*
X189940Y735681D03*
X185440D03*
X182674Y730521D03*
X192949Y771020D03*
X182500Y780786D03*
X189770Y778082D03*
X106650Y779581D03*
X54062Y257049D03*
X68756Y167695D03*
X56190Y170026D03*
X59640Y161376D03*
X57257Y180712D03*
X67853Y180744D03*
X68690Y175589D03*
X55963Y199565D03*
X68930Y197193D03*
X66570Y189983D03*
X57749Y204326D03*
X56383Y218543D03*
X68830Y215817D03*
X63720Y228683D03*
X56936Y223944D03*
X63718Y239030D03*
X81030Y172605D03*
X71510Y164548D03*
X82030Y191733D03*
X75236Y188946D03*
X75359Y201109D03*
X85876Y218939D03*
X78190Y214642D03*
X75560Y218513D03*
X73870Y205758D03*
X72150Y225148D03*
X86479Y249259D03*
X77239Y260814D03*
X79544Y267579D03*
X90878Y177967D03*
X86560Y205852D03*
X88399Y244041D03*
X136470Y481994D03*
X139310Y478102D03*
X146240Y472111D03*
X135300Y468444D03*
X126072Y480864D03*
X129028Y425593D03*
X108026Y492500D03*
X114072Y480964D03*
X105670Y411262D03*
X110490Y397362D03*
X74291Y486665D03*
X85951Y410263D03*
X83245Y397913D03*
X55982Y494543D03*
X101449Y194368D03*
X101020Y223348D03*
X106760Y175370D03*
X106517Y210796D03*
X481340Y593296D03*
X500419Y578644D03*
X487398Y576665D03*
X490658Y579025D03*
X468740Y585897D03*
X460236Y581679D03*
X435319Y600123D03*
X437516Y587579D03*
X429340Y596874D03*
X424904Y586283D03*
X336057Y575657D03*
X299121Y597542D03*
X291357Y586128D03*
X283650Y589044D03*
X278109Y589238D03*
X279658Y574443D03*
X263792Y574203D03*
X274309Y574653D03*
X269609Y576413D03*
X253187Y596382D03*
X253709Y586128D03*
X259678Y581553D03*
X242796Y589749D03*
X234370Y593242D03*
X216590Y570850D03*
X209940Y584893D03*
X198890Y584105D03*
X209590Y580893D03*
X197730Y572893D03*
X201510Y576885D03*
X210040Y576893D03*
X211240Y572893D03*
X193080Y581235D03*
X177830Y583535D03*
X172430Y584035D03*
X166786Y569056D03*
X175386Y569589D03*
X179740Y568951D03*
X166930Y578435D03*
X175330Y578535D03*
X171053Y569411D03*
X162786Y568599D03*
X161280Y581585D03*
X158430Y568437D03*
X154140Y577815D03*
X155109Y561153D03*
X125340Y558090D03*
X132960Y550005D03*
X124279Y523691D03*
X323931Y589733D03*
X319135Y591407D03*
X453775Y600614D03*
X455890Y592792D03*
X485380Y596505D03*
X146100Y323543D03*
X145580Y316836D03*
X162181Y303075D03*
X161687Y310355D03*
X161513Y317143D03*
X151230Y330164D03*
X150918Y318134D03*
X150510Y336306D03*
X195420Y372406D03*
X192681Y377554D03*
X202823Y376922D03*
X197938Y376839D03*
X200439Y390168D03*
X203880Y385272D03*
X200488Y396425D03*
X215120Y399654D03*
X214406Y395539D03*
X152554Y494027D03*
X158406Y500016D03*
X193500Y489796D03*
X202525Y299358D03*
X226255Y472579D03*
X234209Y480953D03*
X228604Y479682D03*
X246465Y464893D03*
X296913Y514460D03*
X301457Y513837D03*
X318968Y536052D03*
X313888Y566003D03*
X332408Y544097D03*
X225199Y287398D03*
X237799Y290548D03*
Y284248D03*
X231499Y287398D03*
Y309448D03*
X250399Y296848D03*
X253611Y293765D03*
X250399Y290548D03*
X244099Y284248D03*
X250399D03*
X244099Y293698D03*
X254334Y298728D03*
X244118Y309387D03*
X254007Y306819D03*
X224209Y494928D03*
X389107Y492097D03*
X374203Y491029D03*
X368943Y506356D03*
X348870Y501571D03*
X355150Y486758D03*
X348220Y486484D03*
X412783Y605500D03*
X394389Y604053D03*
X413105Y613739D03*
X420883Y556729D03*
X431145Y556608D03*
X439762Y515540D03*
Y523757D03*
X442763Y549595D03*
X445838Y538085D03*
X450367Y540720D03*
X482398Y673087D03*
X484700Y660355D03*
X479354Y677054D03*
X478905Y659426D03*
X430140Y665660D03*
X506234Y207368D03*
X489040Y169483D03*
X487080Y180918D03*
X488850Y175419D03*
X486738Y210434D03*
X496360Y167221D03*
X513120Y72069D03*
X524955Y99359D03*
X519625Y108543D03*
X526835Y108314D03*
X522111Y113310D03*
X520068Y207142D03*
X516551Y214987D03*
X536955Y100257D03*
X532955Y108669D03*
X528955Y99781D03*
X532955Y100604D03*
X535960Y112850D03*
X527613Y113373D03*
X542700Y112881D03*
X541657Y207645D03*
X555938Y97292D03*
X551454Y97154D03*
X557995Y110244D03*
X550490Y112989D03*
X544700Y216100D03*
X553909Y207401D03*
X547927Y212190D03*
X558416Y210682D03*
X547148Y220220D03*
X566090Y109136D03*
X560938Y97195D03*
X569559Y103123D03*
X561909Y207393D03*
X572690Y226569D03*
X572020Y222393D03*
X567980Y222353D03*
X568410Y226647D03*
X578938Y103123D03*
X583661Y121836D03*
X580501Y138336D03*
X583829Y132232D03*
X583547Y128232D03*
X581565Y154969D03*
X583970Y144589D03*
X580180Y148894D03*
X579540Y143304D03*
X579897Y161355D03*
X584438Y160933D03*
X582792Y167632D03*
X581915Y179955D03*
X582920Y194220D03*
X588692Y192809D03*
X585580Y210516D03*
X605070Y123991D03*
X600118Y112568D03*
X592938Y133232D03*
X594938Y127893D03*
X592491Y175906D03*
X593277Y179955D03*
X618623Y108918D03*
X610543Y107678D03*
X617925Y114064D03*
X613432Y153528D03*
X628838Y120216D03*
X628738Y133012D03*
X624950Y189801D03*
X638970Y132241D03*
X639200Y170100D03*
X660700Y203282D03*
X660770Y214951D03*
X661160Y235485D03*
X661190Y246085D03*
X657838Y243407D03*
Y238407D03*
X669987Y53672D03*
X670980Y77061D03*
X671810Y106472D03*
X688160Y64459D03*
X687571Y172292D03*
X687584Y251770D03*
X695600Y590788D03*
X707176Y50574D03*
X711676Y51019D03*
X706380Y75482D03*
X708130Y106389D03*
X701770Y331938D03*
X710585Y539103D03*
X701170Y538508D03*
X708258Y549815D03*
X701023Y553658D03*
X710873Y563230D03*
X713300Y578995D03*
X713190Y583032D03*
X712740Y593101D03*
X731566Y442136D03*
X731570Y464043D03*
X727940Y469943D03*
X731340Y476723D03*
X727602Y500100D03*
X729942Y515757D03*
X719761Y532432D03*
X745220Y327250D03*
X741401Y454832D03*
X736310Y450774D03*
X742779Y487639D03*
X743364Y478975D03*
X743150Y483502D03*
X745500Y492500D03*
X738130Y502748D03*
X744020Y566143D03*
X753230Y328262D03*
X759400Y334839D03*
X758223Y446532D03*
X757823Y451032D03*
X758494Y455532D03*
X748723Y455332D03*
X758500Y469500D03*
X757500Y474000D03*
X748300Y496800D03*
X751730Y583047D03*
X524405Y212531D03*
X532320Y209470D03*
X538525Y213425D03*
X491046Y207506D03*
X487839Y194142D03*
X487464Y198566D03*
X640647Y339854D03*
X613640Y336986D03*
X604338Y338285D03*
X598551Y329541D03*
X545981Y236287D03*
X528105Y230594D03*
X536676Y234993D03*
X504160Y255584D03*
X494850Y315733D03*
X524675Y234766D03*
X515675Y234555D03*
X499405Y242877D03*
X649995Y296433D03*
X653352Y291388D03*
X634212Y281670D03*
X591977Y319360D03*
X593607Y305034D03*
X592201Y308988D03*
X596574Y276393D03*
X590874Y275195D03*
X604926Y278476D03*
X594174Y256695D03*
X596774Y249795D03*
X588607Y305034D03*
X585584Y308881D03*
X581474Y274795D03*
X578076Y260093D03*
Y253393D03*
Y246693D03*
X565953Y301635D03*
X561525Y298192D03*
X566876Y289890D03*
X566774Y275195D03*
X564274Y279395D03*
X564676Y253693D03*
Y260093D03*
X571476D03*
X564676Y246693D03*
X571576D03*
X555072Y289563D03*
X557207Y280328D03*
X545223Y276895D03*
X551341Y274262D03*
X557207Y274828D03*
X547929Y258102D03*
X545116Y266847D03*
X545703Y245725D03*
X539267Y267102D03*
X529527Y265584D03*
X539438Y250323D03*
X536576Y246993D03*
X525480Y268959D03*
X515675Y254098D03*
X517670Y247527D03*
X510338Y571325D03*
X515110Y528785D03*
X513480Y541499D03*
X513838Y556925D03*
X534638Y539825D03*
X533038Y590325D03*
X540701Y590162D03*
X527638Y590325D03*
X544138Y530125D03*
X545413Y547950D03*
X551438Y561225D03*
X550938Y587325D03*
X547000Y590163D03*
X556971Y460656D03*
X556959Y443009D03*
X556771Y456156D03*
X540141Y442994D03*
X530038Y444323D03*
X535352Y440414D03*
X529968Y440216D03*
X536440Y431923D03*
X541440Y431787D03*
X523667Y438452D03*
X517929Y439676D03*
X547488Y452373D03*
X546384Y445107D03*
X543381Y448428D03*
X551140Y445789D03*
X600770Y358702D03*
X611848Y359784D03*
X607855Y352341D03*
X618581Y354818D03*
X646013Y358110D03*
X646171Y364676D03*
X679138Y397985D03*
X627084Y578257D03*
X639673Y576888D03*
X651437Y578943D03*
X646732Y580781D03*
X641870Y580743D03*
X646870Y576243D03*
X648701Y624774D03*
X637738Y392034D03*
X627022Y383713D03*
X637614Y397259D03*
X647440Y386383D03*
X641236Y381616D03*
X645236Y377858D03*
X647340Y393283D03*
X647440Y408383D03*
X647340Y400083D03*
X654340Y386283D03*
X661140D03*
X654840Y408483D03*
X661940Y408383D03*
X658295Y417662D03*
G54D31*
X119900Y754021D03*
X125600Y759000D03*
X97390Y766435D03*
X104300Y773100D03*
X458600Y599200D03*
X499225Y205296D03*
X495300Y201600D03*
X510000Y173500D03*
X521320Y178184D03*
X515600Y172800D03*
X516100Y178100D03*
X526621Y177079D03*
X518725Y170525D03*
X496123Y233500D03*
X499075Y235575D03*
X507000Y239000D03*
X635000Y265400D03*
G54D40*
X605796Y174845D03*
Y189845D03*
Y204845D03*
G54D41*
X615657Y92789D03*
G54D38*
X546181Y81889D03*
G54D35*
X162335Y512456D03*
X154475Y530422D03*
X168189Y514331D03*
X173252Y515693D03*
X165707Y506156D03*
X172087Y510536D03*
X223376Y523322D03*
X295047Y554565D03*
G54D36*
X159196Y515612D03*
X243075Y552984D03*
X290322Y549841D03*
X243075Y508891D03*
G54D37*
X514780Y38803D03*
X524780D03*
X534780D03*
X544780D03*
X554780D03*
X577371D03*
X587371D03*
X597371D03*
X607371D03*
X617371D03*
X639963D03*
X649963D03*
X659963D03*
X669963D03*
X679963D03*
G54D33*
X43898Y168544D03*
Y231457D03*
G54D42*
X712975Y165455D03*
Y173455D03*
Y183255D03*
Y252261D03*
Y262061D03*
X723275Y165455D03*
Y173455D03*
Y183255D03*
Y252261D03*
Y262061D03*
G54D39*
X605796Y165160D03*
X609733Y215672D03*
G54D34*
X154900Y551832D03*
X261972Y562431D03*
X277725Y521493D03*
G54D29*
X45282Y321764D03*
Y338300D03*
G54D43*
X711575Y274161D03*
X733975D03*
G54D28*
X25455Y356832D03*
%LPD*%
G75*
G36*
G01X134476Y702308D02*
G02X133588Y703767I0J1000D01*
G03X133940Y704730I-1150J966D01*
G03X131654Y706040I-1502J29D01*
G02X130132Y706893I-522J853D01*
G01Y716989D01*
X130354Y717211D01*
X160514D01*
X160737Y716988D01*
Y705400D01*
X157645Y702308D01*
X134476D01*
G37*
G36*
G01X623042Y613118D02*
X623249Y613325D01*
X644025D01*
X644397Y612953D01*
Y592507D01*
X644066Y592176D01*
X623249D01*
X623042Y592383D01*
Y613118D01*
G37*
G36*
G01X667207Y364359D02*
G02X667636Y364116I0J-500D01*
G03X670214I1289J771D01*
G01X670282Y364229D01*
X670510Y364359D01*
X677630D01*
G02X678130Y363859I0J-500D01*
G01Y355029D01*
G02X677630Y354529I-500J0D01*
G01X655950D01*
G02X655450Y355029I0J500D01*
G01Y363859D01*
G02X655950Y364359I500J0D01*
G01X667207D01*
G37*
G36*
G01X677101Y198112D02*
X676160Y199053D01*
Y238466D01*
X678351Y240657D01*
X726050D01*
X727370Y239337D01*
Y225918D01*
G03Y218804I6605J-3557D01*
G01Y201302D01*
X724180Y198112D01*
X718884D01*
G02X718427Y198408I0J500D01*
G03X704723I-6852J-3053D01*
G02X704266Y198112I-457J204D01*
G01X677101D01*
G37*
G36*
G01X685544Y118486D02*
X684520Y119510D01*
Y157950D01*
X686090Y159520D01*
X755070D01*
X757200Y157390D01*
Y118986D01*
G02X756700Y118486I-500J0D01*
G01X691813D01*
G02X690888Y119868I-1J1000D01*
G03X688112I-1388J573D01*
G02X687187Y118486I-924J-382D01*
G01X685544D01*
G37*
%LPC*%
G75*
G54D30*
X701687Y212132D03*
X700947Y216868D03*
X700994Y221368D03*
X691148Y140140D03*
X691280Y149571D03*
X691314Y145071D03*
G54D43*
X711575Y222361D03*
Y143555D03*
X733975D03*
%LPD*%
G75*
G54D10*
G01X215749Y281098D02*
Y283609D01*
G01X588153Y459599D02*
X590733D01*
X594650Y455682D01*
Y447565D01*
X562692Y415607D01*
Y413177D01*
X552531Y403016D01*
X495907D01*
X430821Y337930D01*
X404026D01*
X390072Y323976D01*
X383953D01*
X373826Y313849D01*
X363225D01*
X360770Y311394D01*
X355790D01*
X355635Y311549D01*
X347531D01*
X345509Y313571D01*
X335337D01*
X334856Y313090D01*
X331720D01*
X327746Y317064D01*
X264255D01*
X258686Y322633D01*
Y339556D01*
X251461Y346781D01*
X247862D01*
X243291Y342210D01*
Y324902D01*
X237005Y318616D01*
X224672D01*
X218947Y312891D01*
G01Y312617D02*
Y312891D01*
G01X243075Y559284D02*
Y563319D01*
X245362Y565606D01*
X246962D01*
X249909Y568553D01*
Y568653D01*
G01X363530Y629731D02*
X363283Y629978D01*
X358027D01*
X357303Y629254D01*
X316520D01*
X315650Y630124D01*
X294798D01*
X278681Y646241D01*
X265620D01*
X258728Y653133D01*
X242240D01*
X241670Y652563D01*
G01D02*
Y653133D01*
X238798Y650261D01*
X235904D01*
X233646Y652519D01*
X233584D01*
G01X241670Y652558D02*
Y652563D01*
G01X390080Y331575D02*
Y331583D01*
X389370Y332293D01*
X385428D01*
X385350Y332215D01*
Y332209D01*
X378320D01*
X373386Y327275D01*
X368445D01*
X364295Y323125D01*
X338442D01*
X337434Y322117D01*
X327913D01*
X325660Y324370D01*
Y328531D01*
X323858Y330333D01*
X320466D01*
X318196Y328063D01*
X314372D01*
X312759Y329676D01*
X307562D01*
X303357Y325471D01*
X292725D01*
X290650Y327546D01*
Y328998D01*
X287564Y332084D01*
X284621D01*
X283548Y331011D01*
X281191D01*
X279718Y332484D01*
Y333694D01*
G01X366140Y407639D02*
X320874D01*
X319410Y409103D01*
Y410079D01*
X316190Y413299D01*
G01X343430Y385937D02*
X344073Y386580D01*
X363111D01*
X363486Y386955D01*
X378227D01*
X378830Y386352D01*
G01X363530Y629731D02*
Y629736D01*
X363770Y629976D01*
X382015D01*
X384537Y632498D01*
X403208D01*
X405061Y634351D01*
X407136D01*
X410514Y630973D01*
X439250D01*
G01X363530Y629727D02*
Y629731D01*
G01X381760Y496004D02*
X394160Y508404D01*
Y511244D01*
X395690Y512774D01*
G01X382960Y711431D02*
Y682623D01*
X379791Y679454D01*
G01X376190Y711259D02*
X379807Y714876D01*
X384990D01*
X386270Y713596D01*
Y689918D01*
X389265Y686923D01*
X390660D01*
G01X396350Y532016D02*
X400570Y527796D01*
Y519399D01*
X395690Y514519D01*
Y512774D01*
G01X404578Y551838D02*
X401010Y548270D01*
Y537581D01*
X396350Y532921D01*
Y532016D01*
G01X405248Y272731D02*
X407938Y270041D01*
Y258457D01*
X405970Y256489D01*
G01X494340Y691623D02*
X493917Y691200D01*
X485522D01*
X483188Y688866D01*
X449662D01*
X442734Y681938D01*
X429935D01*
X426787Y685086D01*
X424044D01*
X418340Y690790D01*
Y694302D01*
X415674Y696968D01*
X414810D01*
G01X446522Y146932D02*
X442147D01*
X439850Y149229D01*
Y188597D01*
X442520Y191267D01*
Y223623D01*
G01X508024Y613598D02*
X510900Y616474D01*
Y618839D01*
X509436Y620303D01*
X495735D01*
X484258Y631780D01*
X465493D01*
X465090Y631377D01*
X463014D01*
X459637Y634754D01*
X443850D01*
G01X452900Y281647D02*
X452770Y281777D01*
Y285497D01*
X451280Y286987D01*
Y293447D01*
X452744Y294911D01*
X453184D01*
X456480Y298207D01*
Y323839D01*
X510801Y378160D01*
X523360D01*
X526034Y380834D01*
X557941D01*
X618870Y441763D01*
Y446404D01*
X628602Y456136D01*
X635120D01*
X-39858Y731383D03*
X-31858D03*
X13170Y372673D03*
X18340Y366452D03*
X13120Y375871D03*
X16010Y369168D03*
X21530Y368991D03*
X14140Y391826D03*
X18210Y386530D03*
X13950Y388616D03*
X13390Y397543D03*
X14240Y394866D03*
X11680Y656335D03*
X9260Y658321D03*
X14000Y658369D03*
X14170Y653991D03*
X9360Y653943D03*
X36567Y73145D03*
X39126Y84631D03*
X34008Y91017D03*
X36567Y107988D03*
X32260Y96899D03*
X38280Y362184D03*
X35750Y364593D03*
X33420Y367309D03*
X23860Y366275D03*
X41685Y73110D03*
X40690Y359555D03*
X53340Y393132D03*
X49750Y387305D03*
X51720Y384808D03*
X50840Y395761D03*
X47820Y398827D03*
X49720Y668412D03*
X56287Y242872D03*
X61945Y267579D03*
X56330Y497940D03*
X58830D03*
X59260Y779815D03*
X58840Y783097D03*
X62290Y779629D03*
X67660Y779452D03*
X62730Y782694D03*
X66860Y782716D03*
X60370Y776861D03*
X64790Y776777D03*
X85010Y171679D03*
X74470Y175666D03*
X82553Y185431D03*
X86172Y213852D03*
X83390Y235665D03*
X79142Y237920D03*
X78373Y276029D03*
X78220Y281745D03*
X78207Y279092D03*
X82560Y288099D03*
X82600Y285426D03*
X90905Y199733D03*
X96990Y223043D03*
X103750Y402740D03*
X103810Y405876D03*
X103870Y399604D03*
X108235Y401017D03*
X111120Y401084D03*
X126220Y80364D03*
Y83291D03*
X129650Y250414D03*
Y255414D03*
X130324Y272096D03*
Y277096D03*
X123960Y283696D03*
X128960D03*
X127705Y489431D03*
X125105D03*
X133138Y510114D03*
X121644Y509398D03*
X130596Y510042D03*
X124652Y509398D03*
X130703Y512549D03*
X130844Y515128D03*
X128087Y513874D03*
X135050Y53493D03*
X137540Y58255D03*
X137990Y296735D03*
X149020Y303498D03*
X139395Y425090D03*
X149477Y532733D03*
X144120Y547577D03*
X146920Y547677D03*
X138198Y712628D03*
X144631Y735955D03*
X147290Y744113D03*
X145040Y740741D03*
X164280Y101810D03*
X164490Y127110D03*
X159190Y127781D03*
X154581Y308767D03*
X150902Y379714D03*
X160886Y380294D03*
X151145Y469456D03*
X162335Y543954D03*
X159185Y537654D03*
X164259Y557273D03*
X154970Y736966D03*
X161981Y730784D03*
X158881D03*
X162640Y743927D03*
X158970D03*
X154400Y744337D03*
X155230Y740259D03*
X167383Y93147D03*
X168850Y99251D03*
X169510Y106579D03*
X173900Y97662D03*
X174710Y105699D03*
X168170Y123367D03*
X173170D03*
X173263Y262589D03*
X176301Y262624D03*
X167322Y255855D03*
X167698Y260617D03*
X175155Y380727D03*
X173381Y424005D03*
X171616Y467804D03*
X166297Y532416D03*
X174395Y527975D03*
X168243Y542706D03*
X169157Y548676D03*
X169444Y558757D03*
X172889Y562710D03*
X177038Y647135D03*
X166388Y647435D03*
X171180Y652009D03*
X171270Y655650D03*
X165599Y730476D03*
X167568Y743335D03*
X194463Y122631D03*
X188658Y256870D03*
X186873Y263697D03*
X185798Y256760D03*
X186873Y260697D03*
X194693Y259197D03*
Y262197D03*
X185074Y380726D03*
X182132Y418327D03*
X184843Y533995D03*
X182480Y566819D03*
X181744Y694829D03*
X181950Y698191D03*
X204003Y91247D03*
X200480Y97687D03*
X212423Y104957D03*
X208908Y96975D03*
X210305Y259330D03*
Y262289D03*
X201994Y261248D03*
X200977Y256305D03*
X202402Y263713D03*
X200469Y259139D03*
X210303Y268227D03*
Y271227D03*
X203149Y281098D03*
X206299Y315748D03*
X203058Y315593D03*
X200590Y327615D03*
X205790Y387003D03*
X210880Y402359D03*
X206380Y402201D03*
X211287Y528547D03*
X212342Y536729D03*
X199539Y537112D03*
X204309Y539953D03*
X204024Y604135D03*
Y609135D03*
X215773Y90147D03*
X220200Y93561D03*
X214320Y101978D03*
X213908Y96975D03*
X219510Y101338D03*
X216512Y258490D03*
X225973Y262197D03*
X216109Y265139D03*
Y262139D03*
X218508Y256664D03*
X216109Y271139D03*
X215749Y281098D03*
X225160Y293676D03*
X225199Y290548D03*
Y284248D03*
X222049Y287398D03*
X215749Y293698D03*
Y287398D03*
X225199Y306298D03*
Y312598D03*
X222049Y306298D03*
X218899D03*
X222049Y299998D03*
X218899Y303148D03*
X218947Y312617D03*
X222974Y356134D03*
X216633Y384989D03*
X213710Y402237D03*
X213994Y466054D03*
X228242Y463681D03*
X223953Y463550D03*
X212809Y479053D03*
X215409Y479253D03*
X219309Y489353D03*
X222209D03*
X224209Y491853D03*
X219960Y596373D03*
Y601373D03*
X212635Y665604D03*
X227650Y720791D03*
X224410Y719970D03*
X225940Y733671D03*
Y736437D03*
X243373Y88767D03*
X239563Y92077D03*
X242913Y106157D03*
X231710Y243642D03*
Y240242D03*
X233793Y260697D03*
X239569Y260639D03*
X234649Y281098D03*
X237865Y281131D03*
X231450Y290583D03*
X237760Y293692D03*
X237799Y287398D03*
X240949Y290548D03*
Y287398D03*
X231499Y284248D03*
Y296848D03*
Y293698D03*
Y299998D03*
X237799Y312598D03*
X231499D03*
X240949Y309448D03*
X228729Y385227D03*
X241451Y392147D03*
X235319Y464362D03*
X233309Y472553D03*
X237609Y472453D03*
X241909Y472553D03*
X234500Y637685D03*
X241670Y652558D03*
X233584Y652519D03*
X236120Y704173D03*
X234940Y733355D03*
X243940Y736412D03*
X239500Y733523D03*
X230440Y724242D03*
X234940Y736392D03*
X252683Y105867D03*
X253558Y95038D03*
X248558D03*
X249453Y114307D03*
X247389Y259139D03*
X256553Y256881D03*
X249433Y263697D03*
Y260697D03*
X256916Y262609D03*
X257253Y259197D03*
X244099Y281098D03*
X254234Y281622D03*
X250399Y281098D03*
X257253Y271197D03*
Y268197D03*
X244110Y290505D03*
X257447Y287117D03*
X244099Y287398D03*
X250399D03*
X253549Y290548D03*
X247249Y296848D03*
X244099D03*
X254631Y324716D03*
X255509Y472253D03*
X246109Y472465D03*
X251309Y472553D03*
X249909Y568653D03*
X248530Y721829D03*
X250630Y719457D03*
X252940Y733567D03*
X263703Y93847D03*
X262473Y106937D03*
X263683Y99902D03*
X269192Y248209D03*
X272242Y244842D03*
X272620Y238653D03*
X267118Y245587D03*
X271458Y241347D03*
X270260Y237037D03*
X266187Y249852D03*
X260068Y262187D03*
X263268Y262370D03*
X263774Y256464D03*
X269263Y252800D03*
X263029Y271139D03*
Y268139D03*
X269380Y302736D03*
X265318Y326487D03*
X267030Y330147D03*
X262247Y334502D03*
X266882Y388165D03*
X264421Y384812D03*
X265532Y422648D03*
X273509Y471649D03*
X260609Y472453D03*
X264909Y472553D03*
X269109Y472353D03*
X266610Y654171D03*
X270040Y651241D03*
X269640Y655290D03*
X261890Y664761D03*
X265550Y668415D03*
X274360Y673831D03*
X267240Y682519D03*
X269420Y677062D03*
X273510Y699749D03*
X266170Y694826D03*
X271210Y718000D03*
X279161Y237817D03*
X276904Y252550D03*
X290363Y286082D03*
X286132Y285953D03*
X277020Y302298D03*
X288466Y325343D03*
X279718Y333694D03*
X275602Y343811D03*
X288220Y389630D03*
X287067Y402358D03*
X287567Y470649D03*
Y467649D03*
X277470Y481197D03*
X280970D03*
X288009Y495653D03*
X289365Y665845D03*
Y673719D03*
X279843Y675688D03*
X275710Y681593D03*
X284760Y707022D03*
X278370Y705093D03*
X289060Y722193D03*
X281830Y722184D03*
X285130Y714433D03*
X289150Y718548D03*
X280210Y734805D03*
X288390Y734796D03*
X284532Y747493D03*
X296176Y249585D03*
X299776Y248010D03*
X301511Y262204D03*
X300477Y265010D03*
X296210Y253187D03*
X300310Y253842D03*
Y257242D03*
X292710Y266542D03*
X301473Y282650D03*
X297810Y280709D03*
X301723Y279150D03*
X301182Y291966D03*
X294382D03*
X305132Y286867D03*
X298332D03*
X301732D03*
X298452Y340487D03*
X303759Y331478D03*
X293290Y389737D03*
X303631Y475607D03*
Y472607D03*
X297370Y498563D03*
X300209Y495853D03*
X301070Y655920D03*
X292850Y656359D03*
X302772Y659604D03*
X301360Y652183D03*
X300880Y664296D03*
X295890Y662662D03*
X295950Y689520D03*
X293068Y677108D03*
X293300Y718944D03*
X302810Y733807D03*
X298590Y733669D03*
X295700Y733133D03*
X293440Y748380D03*
X311290Y247249D03*
X312680Y258353D03*
X316190Y413299D03*
X319478Y429389D03*
X308220Y432552D03*
X318950Y432473D03*
X317492Y618193D03*
X320360Y642275D03*
X314614Y690767D03*
X316165Y693404D03*
X307280Y733705D03*
X321930Y724895D03*
X314930Y724533D03*
X335668Y92822D03*
X330668D03*
X325360Y92517D03*
X324070Y88861D03*
X327430Y108208D03*
X327190Y103818D03*
X337630Y106304D03*
X334720Y102184D03*
X336720Y310846D03*
X332700Y333089D03*
X329110Y623514D03*
X330440Y639504D03*
X328032Y642674D03*
X337070Y639759D03*
X332710Y642694D03*
X335390Y667895D03*
X326890Y676159D03*
X337798Y686721D03*
X336110Y693934D03*
X331520Y701642D03*
X330410Y712895D03*
X329590Y724283D03*
X338270Y733387D03*
X338460Y724585D03*
X346600Y38561D03*
X346150Y36030D03*
X353060Y61504D03*
X340543Y88647D03*
X343070Y99372D03*
X341693Y286010D03*
X352420Y375672D03*
X343430Y385937D03*
X343770Y382166D03*
X352890Y479656D03*
X348000Y479150D03*
X352260Y483029D03*
X352160Y502138D03*
X351250Y499752D03*
X353400Y507260D03*
X353460Y504536D03*
X348190Y511550D03*
X353120Y510003D03*
X350690Y516376D03*
X352940Y518025D03*
X340340Y638054D03*
X340669Y644827D03*
X340630Y655093D03*
X340530Y675658D03*
X351720Y670018D03*
X338970Y670776D03*
X340870Y665042D03*
X339300Y716800D03*
X342230Y720936D03*
X341190Y712379D03*
X345610Y733982D03*
X354060Y734790D03*
X350720Y745722D03*
X365670Y64458D03*
X362133Y90877D03*
X367776Y91746D03*
X369670Y99845D03*
X361470Y101757D03*
X354943Y104191D03*
X367350Y123927D03*
X367220Y303202D03*
X354690Y377000D03*
X364645Y377065D03*
X364880Y384455D03*
X366140Y407639D03*
X365850Y414874D03*
X354750Y445325D03*
X369918Y592253D03*
X369848Y588903D03*
X363530Y629727D03*
X365990Y645272D03*
X367870Y650239D03*
X364980Y655266D03*
X363340Y650512D03*
X361810Y675011D03*
X365620Y663069D03*
X365380Y668972D03*
X365160Y672922D03*
X361760Y668716D03*
X364320Y680434D03*
X364649Y684022D03*
X364765Y687963D03*
X364115Y692990D03*
X357830Y718682D03*
X364750Y727821D03*
X364090Y748565D03*
X354420Y749198D03*
X357610Y748302D03*
X383247Y64141D03*
X373560Y63973D03*
X372776Y91746D03*
X382087Y103647D03*
X380483Y99047D03*
X378733Y105987D03*
X384863Y95437D03*
X376100Y108780D03*
X376723Y94178D03*
X384248Y319157D03*
X372080Y330574D03*
X379560Y374955D03*
X379720Y372257D03*
X378830Y386352D03*
X382620Y391882D03*
X379300Y380862D03*
X379286Y378015D03*
X379750Y383965D03*
X382190Y388077D03*
X376600Y408045D03*
X371260Y412879D03*
X383750Y437058D03*
X381239Y467171D03*
X381760Y496004D03*
X373448Y589053D03*
X373518Y592403D03*
X379791Y679454D03*
X382960Y711431D03*
X376190Y711259D03*
X375548Y731459D03*
X373500Y748457D03*
X389690Y60665D03*
X392493Y92647D03*
X400163Y99177D03*
X391310Y99570D03*
X399613Y104657D03*
X391233Y96093D03*
X398088Y128455D03*
X393088D03*
X399880Y319568D03*
X390080Y331575D03*
X389740Y404725D03*
X395740Y407528D03*
X393370Y411618D03*
X387080Y486400D03*
X385940Y482478D03*
X388890Y480439D03*
X386410Y477576D03*
X389670Y477262D03*
X395690Y512774D03*
X396350Y532016D03*
X391630Y597900D03*
X400589Y611672D03*
X400587Y607022D03*
X398195Y620821D03*
X400695Y618321D03*
X398195D03*
X400695Y620821D03*
X399363Y653588D03*
X396550Y680266D03*
X390660Y686923D03*
X391910Y696742D03*
X398620Y701411D03*
X400730Y721954D03*
X405970Y256489D03*
X405248Y272731D03*
X410607Y485620D03*
X413607D03*
X404578Y551838D03*
X408736Y551529D03*
X413342Y556219D03*
X405234Y611692D03*
X405249Y607017D03*
X412960Y618207D03*
X410315Y614782D03*
X403970Y642364D03*
X411862Y688027D03*
X412250Y683196D03*
X412878Y693183D03*
X414550Y707464D03*
X414810Y696968D03*
X409010Y726147D03*
X415780Y747078D03*
X421640Y228403D03*
Y223403D03*
X431280Y514223D03*
X431356Y516836D03*
X425999Y516211D03*
X424873Y513921D03*
X428039Y556539D03*
X423861Y556535D03*
X419221Y612253D03*
X422026Y656883D03*
X421080Y665945D03*
X422222Y675226D03*
X426100Y667884D03*
X422981Y690351D03*
X423055Y696713D03*
X427230Y707377D03*
X427130Y717871D03*
X421730Y717398D03*
X424410Y718429D03*
X417330Y717420D03*
X431440Y723955D03*
X424200Y733399D03*
X426440Y724240D03*
X439670Y70044D03*
X446522Y146932D03*
X442520Y223623D03*
X445540Y288853D03*
X444920Y485259D03*
X447770Y485290D03*
X439749Y506523D03*
X447781Y523888D03*
X438722Y538842D03*
X441063Y540563D03*
X448329Y534995D03*
X434187Y556444D03*
X442240Y553337D03*
X441230Y587341D03*
X447830Y588739D03*
X446378Y582681D03*
X443850Y634754D03*
X439250Y630973D03*
X435420Y647117D03*
X437509Y648996D03*
X435972Y655595D03*
X444700Y651900D03*
X435539Y671628D03*
X436445Y667628D03*
X440688Y689438D03*
X440690Y702386D03*
X440688Y694438D03*
X446260Y722014D03*
X444530Y723917D03*
X440660Y712065D03*
X439200Y722093D03*
X442120Y724781D03*
X447680Y733564D03*
X455292Y162797D03*
X455470Y166963D03*
X452669Y157140D03*
X455913Y178698D03*
X459108Y253181D03*
X456530Y256034D03*
X452900Y281647D03*
X453810Y289325D03*
X451790Y300129D03*
X454022Y541052D03*
X450778Y583106D03*
X459950Y722720D03*
X453960Y723142D03*
X449060Y721761D03*
X455410Y734113D03*
X450410Y733682D03*
X451320Y725044D03*
X473950Y172124D03*
X475760Y168747D03*
X472670Y166398D03*
X473580Y177859D03*
X474630Y174843D03*
X468452Y197934D03*
X464810Y311253D03*
X470090Y332824D03*
X475190Y339013D03*
X465913Y402659D03*
X465883Y399834D03*
X480118Y479107D03*
Y474107D03*
X471804Y561085D03*
Y556085D03*
X474946Y659376D03*
X469977Y676496D03*
X469467Y679915D03*
X479409Y682305D03*
X470550Y724034D03*
X465850Y733428D03*
X476160Y734205D03*
X488017Y203716D03*
X487168Y214568D03*
X480830Y333921D03*
X486300Y422150D03*
X481300D03*
X483209Y545250D03*
Y550250D03*
X490600Y608136D03*
X489800Y600200D03*
X491044Y667604D03*
X491060Y671604D03*
X492294Y682347D03*
X483056Y679628D03*
X494340Y691623D03*
X480620Y734244D03*
X499456Y128666D03*
X499154Y194198D03*
X505580Y192555D03*
X511070Y310719D03*
X509140Y338005D03*
X497111Y388567D03*
X502111D03*
X499551Y429636D03*
X497818Y440265D03*
X511230Y499059D03*
X506230D03*
X504613Y525200D03*
X500138Y563025D03*
X500438Y574925D03*
X505738Y590525D03*
X508024Y613598D03*
X504980Y616425D03*
X508400Y617803D03*
X505780Y642543D03*
X501120Y633249D03*
X510700Y634300D03*
X496690Y633589D03*
X505690Y654419D03*
X496453Y670876D03*
X506470Y683512D03*
X496277Y678185D03*
X501540Y681970D03*
X509855Y724107D03*
X500260Y729094D03*
X501604Y733003D03*
X512600Y178900D03*
X512200Y204200D03*
X526443Y194116D03*
X514500Y194300D03*
X525293Y191705D03*
X526657Y207363D03*
X518590Y310129D03*
X526250Y310940D03*
X519650Y320384D03*
X522420Y315475D03*
X517260Y315978D03*
X523930Y321642D03*
X514400Y340829D03*
X520510Y337299D03*
X527438Y340353D03*
X517617Y422944D03*
X526440Y422428D03*
X527300Y417368D03*
X513140Y452621D03*
X519440Y452321D03*
X526340D03*
X516353Y443517D03*
X523838Y442723D03*
X513140Y459721D03*
Y466021D03*
X525640Y473021D03*
X519640D03*
X513140D03*
X521938Y540325D03*
X516380Y540364D03*
X516738Y562425D03*
X513738D03*
X524638Y590225D03*
X520228Y590335D03*
X515438Y649996D03*
X525692Y654862D03*
X521516Y650576D03*
X517806Y670102D03*
X517222Y673917D03*
X518800Y665776D03*
X515541Y661845D03*
X518382Y678247D03*
X515429Y692278D03*
Y697278D03*
X516940Y735683D03*
X521800Y732667D03*
X514420Y733131D03*
X524576Y733227D03*
X542180Y93534D03*
X529272Y178311D03*
X542002Y180100D03*
X532500Y206500D03*
X535772Y250076D03*
X528680Y317349D03*
X541380Y340358D03*
X543110Y333848D03*
X536180Y341432D03*
X536170Y336603D03*
X531795Y340409D03*
X531430Y337074D03*
X527603Y337208D03*
X540700Y418852D03*
X541650Y422280D03*
X536440Y421973D03*
X533040Y453221D03*
X534738Y445523D03*
X541838Y450723D03*
X533740Y458021D03*
Y465021D03*
Y473021D03*
X541538Y529625D03*
X534401Y529562D03*
X535776Y590487D03*
X530338Y590325D03*
X532479Y633588D03*
X529525Y669349D03*
X529899Y661020D03*
X539734Y675020D03*
X539577Y721891D03*
X532940Y734810D03*
X531029Y733142D03*
X547480Y96632D03*
X550604Y168072D03*
X557668Y176534D03*
X555510Y173872D03*
X551395Y174172D03*
X549909Y207060D03*
X557909Y207537D03*
X555750Y212029D03*
X544500Y207000D03*
X545424Y226722D03*
X546690Y233066D03*
X544990Y231086D03*
X549488Y233003D03*
X549358Y230153D03*
X552120Y232388D03*
X552050Y229124D03*
X553690Y340829D03*
X547340Y339103D03*
X548470Y378127D03*
X544500Y422583D03*
X557017Y438968D03*
X549574Y432582D03*
X555140Y445940D03*
X543338Y459323D03*
X551538Y540325D03*
X551338Y544225D03*
X551438Y563825D03*
X551238Y584025D03*
X543850Y590313D03*
X552849Y631652D03*
X549314Y647594D03*
X551230Y652844D03*
X544934Y720820D03*
X555551Y722342D03*
X544082Y724460D03*
X549049Y724412D03*
X557978Y734053D03*
X565938Y96820D03*
X563129Y178369D03*
X559646Y174476D03*
X572782Y195199D03*
X565310Y412700D03*
X565977Y456156D03*
X566059Y460956D03*
X571790Y646799D03*
X559440Y650767D03*
X566950Y659439D03*
X563850Y659575D03*
X563840Y653515D03*
X563586Y682137D03*
X563441Y676872D03*
X565168Y679614D03*
X563393Y686908D03*
X565168Y699614D03*
X560544Y718091D03*
X569604Y721248D03*
X574190Y717805D03*
X571232Y732545D03*
X587968Y138765D03*
X575880Y293016D03*
X575908Y295606D03*
X579788Y354743D03*
X578830Y448192D03*
X588153Y459599D03*
X583890Y537093D03*
X588780Y611056D03*
Y616056D03*
X577217Y652002D03*
X576987Y660180D03*
X580740Y653286D03*
X580637Y663629D03*
X579076Y669603D03*
X576520Y667750D03*
X576644Y679562D03*
X579220Y720776D03*
X580510Y724421D03*
X593537Y161023D03*
X592917Y171906D03*
X590720Y456076D03*
X591100Y450128D03*
X603819Y485332D03*
X605290Y594166D03*
X602314Y607641D03*
Y602641D03*
X596998Y658008D03*
X591840Y659568D03*
X602332Y671156D03*
X600736Y668425D03*
X597300Y663128D03*
X600650Y707835D03*
X595950Y708997D03*
X603938Y753623D03*
X617778Y238873D03*
X612974Y269095D03*
X609150Y328514D03*
X616490Y327534D03*
X619190Y336986D03*
X608306Y359971D03*
X617592Y362539D03*
X620238Y364369D03*
X617980Y460408D03*
X611254Y617943D03*
X615690Y625536D03*
X615700Y657757D03*
X608975Y708094D03*
X612914Y707630D03*
X613730Y717663D03*
X620830Y717516D03*
X609840Y713617D03*
X622470Y261628D03*
X632376Y305257D03*
X631702Y307880D03*
X632122Y312898D03*
X633773Y310439D03*
X635652Y313118D03*
X636962Y310928D03*
X623820Y321062D03*
X633470Y326710D03*
X628140Y317610D03*
X631860Y321455D03*
X627000Y327926D03*
X622890Y325227D03*
X633652Y315198D03*
X630190Y336986D03*
X625190D03*
X624889Y357778D03*
X636938Y402885D03*
X626250Y450248D03*
X635120Y456136D03*
X622100Y465822D03*
X625900Y461769D03*
X628250Y471142D03*
X636010Y469995D03*
X630420Y491511D03*
X636170Y493028D03*
X622600Y488753D03*
X634921Y580163D03*
X627047Y581066D03*
X636868Y593141D03*
X630768Y593241D03*
X624468D03*
Y612141D03*
X624368Y605941D03*
Y599741D03*
X629868Y612241D03*
X635968D03*
X627986Y625895D03*
X633970Y723033D03*
X622290Y708516D03*
X631690Y733744D03*
X635460Y735130D03*
X630040Y745114D03*
X639350Y250123D03*
X652362Y306598D03*
X648450Y338711D03*
X648838Y349785D03*
X642863Y358010D03*
X647280Y446851D03*
X653360Y446280D03*
X651080Y455238D03*
X651840Y460012D03*
X648920Y457851D03*
X646600Y463571D03*
X650150Y494337D03*
X638166Y560972D03*
X638286Y557415D03*
X643568Y593241D03*
Y612341D03*
Y606641D03*
Y599541D03*
X642795Y624818D03*
X642999Y685781D03*
X638890Y734879D03*
X638470Y762212D03*
X649640Y757527D03*
X656270Y299379D03*
X654962Y307698D03*
X654060Y302459D03*
X659350Y298810D03*
X656730Y338633D03*
X666270Y359134D03*
X653938Y364885D03*
X669215Y377488D03*
X658680Y446610D03*
X654240Y511568D03*
X655978Y609635D03*
X656505Y701191D03*
X654050Y718086D03*
X659300Y734119D03*
X654000Y736400D03*
X676590Y188198D03*
X680100Y188182D03*
X680220Y200725D03*
X678650Y203480D03*
X681770Y203514D03*
X682140Y191214D03*
Y194615D03*
X680310Y217357D03*
X678750Y214908D03*
X681870Y214942D03*
X678986Y392661D03*
X678838Y407785D03*
X672660Y441007D03*
X679299Y491473D03*
X678450Y508438D03*
X678360Y557426D03*
X673950Y557314D03*
X677850Y562515D03*
X673700D03*
X677730Y567706D03*
X673590Y567696D03*
X678386Y668420D03*
X673386D03*
X698150Y136791D03*
X687546Y154228D03*
X699990Y149631D03*
X700060Y144981D03*
X693520Y186376D03*
X697850Y186441D03*
X689820Y200159D03*
Y203491D03*
X689480Y191144D03*
Y194615D03*
X691970Y216820D03*
X691690Y212100D03*
X693540Y205721D03*
X697800Y205879D03*
X692010Y221158D03*
X687584Y233034D03*
X692520Y506898D03*
X698386Y667241D03*
X693386D03*
X704550Y444407D03*
X715528Y459332D03*
X710768Y475972D03*
X707920Y505575D03*
X716260Y525295D03*
X709500Y736800D03*
X716245Y765576D03*
X726500Y123466D03*
X726400Y130303D03*
X726470Y126659D03*
X726430Y465371D03*
X720140Y478333D03*
X719370Y472436D03*
X721100Y689400D03*
X731200Y716200D03*
X721245Y765576D03*
X726925Y778490D03*
X731925D03*
X744760Y103711D03*
X744790Y106938D03*
X747710Y100293D03*
X738370Y123395D03*
X745070Y110183D03*
X738270Y130232D03*
X738340Y126588D03*
X747080Y129815D03*
X737350Y464330D03*
Y459823D03*
X751080Y100293D03*
X754580Y124020D03*
X748070Y110209D03*
X751180D03*
X754610Y127247D03*
X750930Y129815D03*
G54D20*
G01X-48870Y332033D02*
X-47720D01*
G01X188658Y256870D02*
X188310D01*
X186075Y254635D01*
X184319D01*
X181341Y251657D01*
X175912D01*
X169416Y245161D01*
Y242722D01*
X168270Y241576D01*
X165874D01*
X163450Y239152D01*
G01X172987Y254355D02*
X175495D01*
X182306Y261166D01*
X184342D01*
X186873Y263697D01*
G01X163604Y241764D02*
X174923Y253083D01*
X179701D01*
X183378Y256760D01*
X185798D01*
G01X178178Y247461D02*
X179375D01*
X182858Y250944D01*
X184057D01*
X187547Y254434D01*
X188984D01*
X190263Y255713D01*
Y257528D01*
X187094Y260697D01*
X186873D01*
G01X201994Y261248D02*
X199887Y263355D01*
Y264400D01*
X196291Y267996D01*
X193152D01*
X191206Y266050D01*
Y253053D01*
X187545Y249392D01*
X183835D01*
X181724Y247281D01*
G01X200469Y259139D02*
X198435Y261173D01*
Y262081D01*
X196705Y263811D01*
X194044D01*
X192320Y262087D01*
Y253035D01*
X184485Y245200D01*
G01X189110Y234754D02*
X191570Y237214D01*
Y244756D01*
X193169Y246355D01*
X194120D01*
X197940Y250175D01*
Y252079D01*
X200977Y255116D01*
Y256305D01*
G01X194481Y241405D02*
X195316Y242240D01*
Y245166D01*
X200140Y249990D01*
Y252057D01*
X203900Y255817D01*
Y262215D01*
X202402Y263713D01*
G01X210305Y259330D02*
Y257313D01*
X208016Y255024D01*
Y251087D01*
X206021Y249092D01*
G01X201032Y244202D02*
Y246803D01*
X204277Y250048D01*
Y252914D01*
X206366Y255003D01*
Y259209D01*
X207310Y260153D01*
Y261198D01*
X206366Y262142D01*
Y264319D01*
X206880Y264833D01*
Y266854D01*
X207431Y267405D01*
X209452D01*
X210274Y268227D01*
X210303D01*
G01X210305Y262289D02*
X211916Y260678D01*
Y257759D01*
X212716Y256959D01*
Y254887D01*
X210080Y252251D01*
Y250424D01*
X207496Y247840D01*
Y238862D01*
X203780Y235146D01*
Y233803D01*
G01X196730Y242692D02*
Y244431D01*
X203136Y250837D01*
Y253399D01*
X205438Y255701D01*
Y269459D01*
X207816Y271837D01*
X209693D01*
X210303Y271227D01*
G01X229569Y535653D02*
X230854D01*
G01X216512Y258490D02*
Y255363D01*
X217886Y253989D01*
Y251287D01*
X213790Y247191D01*
Y229860D01*
G01X233626Y537236D02*
X232052Y538810D01*
X229752D01*
G01X228998Y541962D02*
X232052D01*
G01X229745Y545120D02*
X234517D01*
X235809Y544214D01*
X236776Y543536D01*
G01X215170Y229721D02*
Y245063D01*
X221516Y251409D01*
Y253656D01*
X218508Y256664D01*
G01X223416Y252487D02*
Y253988D01*
X220922Y256482D01*
Y263849D01*
X216184Y268587D01*
G01X235216Y239292D02*
X239186Y243262D01*
Y246377D01*
X246183Y253374D01*
X247470D01*
X251597Y257501D01*
Y262438D01*
X253700Y264541D01*
Y267646D01*
X257251Y271197D01*
X257253D01*
G01X216109Y271139D02*
X222036Y265212D01*
Y257106D01*
X224035Y255107D01*
X224885Y254256D01*
G01X236516Y237381D02*
Y238822D01*
X240960Y243266D01*
Y246405D01*
X246489Y251934D01*
X247280D01*
X252576Y257230D01*
Y262189D01*
X253372Y262985D01*
X253897D01*
X255941Y265029D01*
X256235D01*
X257253Y266047D01*
Y268197D01*
G01X240650Y234122D02*
Y238392D01*
X245316Y243058D01*
Y245644D01*
X256553Y256881D01*
G01X238780Y238483D02*
X243268Y242971D01*
Y246968D01*
X247086Y250786D01*
X247496D01*
X253482Y256772D01*
Y261177D01*
X254755Y262450D01*
Y262711D01*
X256253Y264209D01*
X257402D01*
X259997Y266804D01*
Y268107D01*
X263029Y271139D01*
G01X262305Y249320D02*
X263527Y250542D01*
Y252117D01*
X265400Y253990D01*
Y260238D01*
X263268Y262370D01*
G01X228609Y516774D02*
X237622D01*
X238341Y517493D01*
Y519887D01*
G01X228609Y523063D02*
X234762D01*
G01X227868Y525251D02*
X228821Y526204D01*
X234275D01*
X234565Y525914D01*
X235217D01*
G01X234762Y523063D02*
X235209Y522616D01*
G01D02*
Y520005D01*
X235310Y519904D01*
G01X238341Y519887D02*
Y522922D01*
X237889Y523374D01*
G01X235310Y519904D02*
X228709D01*
G01X235310D02*
X238324D01*
X238341Y519887D01*
G01X260068Y262187D02*
X260616Y261639D01*
Y256173D01*
X257434Y252991D01*
Y250890D01*
X255798Y249254D01*
G01X260051Y248883D02*
X262509Y251341D01*
Y254159D01*
X263774Y255424D01*
Y256464D01*
G01X263029Y268139D02*
X261426Y266536D01*
Y263798D01*
X261668Y263556D01*
Y260599D01*
X261426Y260357D01*
Y251811D01*
X260146Y250531D01*
X259933D01*
X257780Y248378D01*
G01X249433Y263697D02*
X249828D01*
X250244Y264113D01*
Y266040D01*
X249880Y266404D01*
Y267604D01*
X250244Y267968D01*
Y269446D01*
X249867Y269823D01*
Y271023D01*
X250244Y271400D01*
Y272632D01*
X253309Y275697D01*
X258083D01*
X258793Y274987D01*
X261689D01*
X261937Y275235D01*
Y282449D01*
X263009Y283521D01*
X267789D01*
X267964Y283696D01*
X268064D01*
G01X249433Y260697D02*
Y261434D01*
X251044Y263045D01*
Y272300D01*
X253641Y274897D01*
X257751D01*
X258461Y274187D01*
X262021D01*
X262737Y274903D01*
Y282117D01*
X263341Y282721D01*
X267789D01*
X267964Y282546D01*
X268064D01*
G01X273200Y258304D02*
X271001D01*
X264536Y251839D01*
Y248167D01*
X265191Y247512D01*
X265193D01*
X267118Y245587D01*
G01X266187Y249852D02*
X266185Y249854D01*
Y252174D01*
X268542Y254531D01*
X270797D01*
X276638Y248690D01*
X283587D01*
X287616Y244661D01*
Y242900D01*
X287104Y242388D01*
G01X283942Y242827D02*
Y246368D01*
X282942Y247368D01*
X276285D01*
X273841Y249812D01*
X270591D01*
X269263Y251140D01*
Y252800D01*
G01X276904Y252550D02*
X279786Y249668D01*
X285248D01*
X288516Y246400D01*
Y242643D01*
X288915Y242244D01*
G01X296210Y253187D02*
X294082Y251059D01*
Y245695D01*
X294830Y244947D01*
G01X297330Y231423D02*
Y248431D01*
X296176Y249585D01*
G01X299830Y230482D02*
Y231988D01*
X299410Y232408D01*
Y247644D01*
X299776Y248010D01*
G01X303681Y262515D02*
X301186Y265010D01*
X300477D01*
G01X292710Y266542D02*
X294194Y265058D01*
X296858D01*
X298460Y266660D01*
X302620D01*
G01X301473Y282650D02*
Y281668D01*
X305322Y277819D01*
G01X310405Y283915D02*
X308486D01*
X306970Y285431D01*
Y287311D01*
X305794Y288487D01*
X301016D01*
X300016Y287487D01*
Y286179D01*
X297810Y283973D01*
Y280709D01*
G01X301182Y291966D02*
X307738D01*
X308280Y291424D01*
G01X310311Y288918D02*
X308060D01*
X306612Y290366D01*
X295982D01*
X294382Y291966D01*
G01X310325Y286418D02*
X309225D01*
X306139Y289504D01*
X300614D01*
X299155Y288045D01*
Y287690D01*
X298332Y286867D01*
G54D11*
X23628Y321764D03*
Y338300D03*
G54D21*
G01X174720Y531356D02*
Y529929D01*
X176345Y528304D01*
Y527644D01*
X184392Y519597D01*
Y513661D01*
X185757Y512296D01*
X200465D01*
X208402Y520233D01*
X211949Y526258D01*
Y527885D01*
X211287Y528547D01*
G01X214118Y528583D02*
X213359Y527824D01*
Y525873D01*
X209527Y519362D01*
X201050Y510886D01*
X185172D01*
X182982Y513076D01*
Y519012D01*
X174935Y527059D01*
Y527435D01*
X174395Y527975D01*
G01X167027Y539526D02*
Y538636D01*
X167500Y538163D01*
X169119D01*
X170809Y539853D01*
X171909D01*
X172209Y540153D01*
X175609D01*
X176651Y541195D01*
X185156D01*
X186637Y542676D01*
X190591D01*
X193221Y540046D01*
X194583D01*
X195288Y540751D01*
Y541356D01*
X195287Y541357D01*
X196157Y542227D01*
X196764D01*
X198294Y543757D01*
X198779D01*
X199239Y544217D01*
X200469D01*
X200929Y543757D01*
X202159D01*
X202619Y544217D01*
X203849D01*
X204309Y543757D01*
X205029D01*
X206514Y542272D01*
Y540748D01*
X207309Y539953D01*
G01X167027Y536376D02*
X167404Y536753D01*
X169704D01*
X171394Y538443D01*
X172494D01*
X172794Y538743D01*
X176194D01*
X177236Y539785D01*
X185741D01*
X187222Y541266D01*
X190006D01*
X192636Y538636D01*
X195168D01*
X198879Y542347D01*
X204444D01*
X205104Y541687D01*
Y540748D01*
X204309Y539953D01*
G01X678386Y668420D02*
X676591Y670215D01*
Y671145D01*
X678523Y673077D01*
X679693Y673491D01*
X680238Y673229D01*
X681400Y673640D01*
X681659Y674186D01*
X682821Y674597D01*
X683366Y674335D01*
X684528Y674746D01*
X684787Y675292D01*
X687167Y676134D01*
X688722D01*
X691488Y677532D01*
X692196Y677298D01*
X693295Y677854D01*
X693527Y678564D01*
X694626Y679120D01*
X695334Y678886D01*
X696433Y679442D01*
X696665Y680152D01*
X697764Y680708D01*
X699803Y681740D01*
X700964Y682328D01*
X702855Y684119D01*
X712820Y694084D01*
Y757675D01*
X713270Y758125D01*
Y759355D01*
X712820Y759805D01*
Y761035D01*
X713270Y761485D01*
Y762715D01*
X712820Y763165D01*
Y767898D01*
X713070Y768604D01*
X713071Y768607D01*
X713620Y768870D01*
X714031Y770032D01*
X713766Y770581D01*
X714177Y771743D01*
X714726Y772006D01*
X715137Y773168D01*
X714872Y773717D01*
X715062Y774256D01*
X715858Y775052D01*
X716528D01*
X717397Y775921D01*
Y776591D01*
X718941Y778134D01*
X719206Y778320D01*
X719716Y778558D01*
X720427Y778297D01*
X721543Y778816D01*
X721802Y779528D01*
X722920Y780048D01*
X723631Y779787D01*
X724747Y780306D01*
X725006Y781018D01*
X726368Y781652D01*
X726651Y781726D01*
X728270D01*
X728720Y781276D01*
Y780285D01*
X726925Y778490D01*
G01X673386Y668420D02*
X675181Y670215D01*
Y671730D01*
X677751Y674301D01*
X686925Y677544D01*
X688385D01*
X700143Y683494D01*
X701871Y685130D01*
X711410Y694669D01*
Y768140D01*
X713838Y775027D01*
X718031Y779220D01*
X718435Y779502D01*
Y779517D01*
X725932Y783005D01*
X725966D01*
X726470Y783136D01*
X728855D01*
X730130Y781861D01*
Y780285D01*
X731925Y778490D01*
G01X716245Y765576D02*
X718040Y767371D01*
Y768848D01*
X719581Y770389D01*
X722906D01*
X725840Y767455D01*
Y760665D01*
X718252Y692934D01*
X696591Y671273D01*
Y669036D01*
X698386Y667241D01*
G01X721245Y765576D02*
X719450Y767371D01*
Y768263D01*
X720166Y768979D01*
X722321D01*
X724430Y766870D01*
Y760744D01*
X724259Y759225D01*
X723478Y758604D01*
X723340Y757380D01*
X723965Y756601D01*
X723827Y755377D01*
X723046Y754756D01*
X722908Y753532D01*
X723533Y752753D01*
X723395Y751529D01*
X722614Y750908D01*
X722476Y749684D01*
X723101Y748905D01*
X722963Y747681D01*
X722182Y747060D01*
X722044Y745836D01*
X722669Y745057D01*
X722531Y743833D01*
X721750Y743212D01*
X721612Y741988D01*
X722237Y741209D01*
X722099Y739985D01*
X721318Y739364D01*
X721180Y738140D01*
X721805Y737361D01*
X721667Y736137D01*
X720886Y735516D01*
X720748Y734292D01*
X721373Y733513D01*
X721235Y732289D01*
X720454Y731668D01*
X720316Y730444D01*
X720941Y729665D01*
X720803Y728441D01*
X720509Y725816D01*
X716905Y693582D01*
X695181Y671858D01*
Y669036D01*
X693386Y667241D01*
G54D12*
X36024Y205257D03*
G54D22*
G01X38493Y-241864D02*
Y-246864D01*
G01X37036Y-241864D02*
X39950D01*
G01X44860Y-246864D02*
X42326D01*
Y-241864D01*
X44860D01*
G01X43846Y-244281D02*
X42326D01*
G01X47426Y-241864D02*
Y-246864D01*
X49960D01*
G01X53793Y-247031D02*
X53666Y-246947D01*
Y-246781D01*
X53793Y-246697D01*
X53920Y-246781D01*
Y-246947D01*
X53793Y-247031D01*
G01Y-244781D02*
X53666Y-244697D01*
Y-244531D01*
X53793Y-244447D01*
X53920Y-244531D01*
Y-244697D01*
X53793Y-244781D01*
G01X58576Y-248531D02*
X57943Y-247697D01*
X57626Y-246864D01*
Y-243531D01*
X57943Y-242697D01*
X58576Y-241864D01*
G01X63993D02*
X63486Y-242031D01*
X63106Y-242447D01*
X62853Y-242947D01*
X62663Y-243614D01*
X62600Y-244364D01*
X62663Y-245114D01*
X62853Y-245781D01*
X63106Y-246281D01*
X63486Y-246697D01*
X63993Y-246864D01*
X64500Y-246697D01*
X64880Y-246281D01*
X65133Y-245781D01*
X65323Y-245114D01*
X65386Y-244364D01*
X65323Y-243614D01*
X65133Y-242947D01*
X64880Y-242447D01*
X64500Y-242031D01*
X63993Y-241864D01*
G01X67700Y-245864D02*
X68080Y-246447D01*
X68586Y-246781D01*
X69156Y-246864D01*
X69663Y-246781D01*
X70170Y-246364D01*
X70486Y-245864D01*
X70550Y-245364D01*
X70423Y-244781D01*
X69980Y-244364D01*
X69536Y-244197D01*
X68966D01*
G01X69536D02*
X69916Y-243947D01*
X70233Y-243531D01*
X70360Y-243031D01*
X70233Y-242531D01*
X69916Y-242114D01*
X69346Y-241864D01*
X68776Y-241947D01*
X68206Y-242281D01*
G01X74510Y-248531D02*
X75143Y-247697D01*
X75460Y-246864D01*
Y-243531D01*
X75143Y-242697D01*
X74510Y-241864D01*
G01X77900Y-245864D02*
X78280Y-246447D01*
X78786Y-246781D01*
X79356Y-246864D01*
X79863Y-246781D01*
X80370Y-246364D01*
X80686Y-245864D01*
X80750Y-245364D01*
X80623Y-244781D01*
X80180Y-244364D01*
X79736Y-244197D01*
X79166D01*
G01X79736D02*
X80116Y-243947D01*
X80433Y-243531D01*
X80560Y-243031D01*
X80433Y-242531D01*
X80116Y-242114D01*
X79546Y-241864D01*
X78976Y-241947D01*
X78406Y-242281D01*
G01X83190Y-242697D02*
X83570Y-242197D01*
X84013Y-241947D01*
X84520Y-241864D01*
X85153Y-242031D01*
X85596Y-242447D01*
X85723Y-242947D01*
X85660Y-243447D01*
X85406Y-243864D01*
X84140Y-244697D01*
X83570Y-245281D01*
X83190Y-246114D01*
X83063Y-246864D01*
X85723D01*
G01X89366D02*
X89493Y-245781D01*
X89683Y-244864D01*
X89936Y-244031D01*
X90253Y-243114D01*
X90760Y-241864D01*
X88226D01*
G01X93770Y-245197D02*
X95416D01*
G01X98490Y-242697D02*
X98870Y-242197D01*
X99313Y-241947D01*
X99820Y-241864D01*
X100453Y-242031D01*
X100896Y-242447D01*
X101023Y-242947D01*
X100960Y-243447D01*
X100706Y-243864D01*
X99440Y-244697D01*
X98870Y-245281D01*
X98490Y-246114D01*
X98363Y-246864D01*
X101023D01*
G01X103400Y-245864D02*
X103780Y-246447D01*
X104286Y-246781D01*
X104856Y-246864D01*
X105363Y-246781D01*
X105870Y-246364D01*
X106186Y-245864D01*
X106250Y-245364D01*
X106123Y-244781D01*
X105680Y-244364D01*
X105236Y-244197D01*
X104666D01*
G01X105236D02*
X105616Y-243947D01*
X105933Y-243531D01*
X106060Y-243031D01*
X105933Y-242531D01*
X105616Y-242114D01*
X105046Y-241864D01*
X104476Y-241947D01*
X103906Y-242281D01*
G01X110653Y-246864D02*
Y-241864D01*
X108310Y-245447D01*
X111476D01*
G01X113600Y-246114D02*
X113980Y-246531D01*
X114423Y-246781D01*
X114993Y-246864D01*
X115563Y-246697D01*
X116006Y-246364D01*
X116323Y-245781D01*
X116386Y-245114D01*
X116260Y-244447D01*
X115943Y-244031D01*
X115500Y-243697D01*
X115056Y-243614D01*
X114613Y-243697D01*
X114043Y-244031D01*
X114233Y-241864D01*
X115943D01*
G01X123990Y-246864D02*
Y-241864D01*
X126396D01*
G01X125510Y-244281D02*
X123990D01*
G01X128710Y-246864D02*
X130293Y-241864D01*
X131876Y-246864D01*
G01X131306Y-245114D02*
X129280D01*
G01X134063Y-246864D02*
X136723Y-241864D01*
G01X134063D02*
X136723Y-246864D01*
G01X140493Y-247031D02*
X140366Y-246947D01*
Y-246781D01*
X140493Y-246697D01*
X140620Y-246781D01*
Y-246947D01*
X140493Y-247031D01*
G01Y-244781D02*
X140366Y-244697D01*
Y-244531D01*
X140493Y-244447D01*
X140620Y-244531D01*
Y-244697D01*
X140493Y-244781D01*
G01X145276Y-248531D02*
X144643Y-247697D01*
X144326Y-246864D01*
Y-243531D01*
X144643Y-242697D01*
X145276Y-241864D01*
G01X150693D02*
X150186Y-242031D01*
X149806Y-242447D01*
X149553Y-242947D01*
X149363Y-243614D01*
X149300Y-244364D01*
X149363Y-245114D01*
X149553Y-245781D01*
X149806Y-246281D01*
X150186Y-246697D01*
X150693Y-246864D01*
X151200Y-246697D01*
X151580Y-246281D01*
X151833Y-245781D01*
X152023Y-245114D01*
X152086Y-244364D01*
X152023Y-243614D01*
X151833Y-242947D01*
X151580Y-242447D01*
X151200Y-242031D01*
X150693Y-241864D01*
G01X154400Y-245864D02*
X154780Y-246447D01*
X155286Y-246781D01*
X155856Y-246864D01*
X156363Y-246781D01*
X156870Y-246364D01*
X157186Y-245864D01*
X157250Y-245364D01*
X157123Y-244781D01*
X156680Y-244364D01*
X156236Y-244197D01*
X155666D01*
G01X156236D02*
X156616Y-243947D01*
X156933Y-243531D01*
X157060Y-243031D01*
X156933Y-242531D01*
X156616Y-242114D01*
X156046Y-241864D01*
X155476Y-241947D01*
X154906Y-242281D01*
G01X161210Y-248531D02*
X161843Y-247697D01*
X162160Y-246864D01*
Y-243531D01*
X161843Y-242697D01*
X161210Y-241864D01*
G01X164600Y-245864D02*
X164980Y-246447D01*
X165486Y-246781D01*
X166056Y-246864D01*
X166563Y-246781D01*
X167070Y-246364D01*
X167386Y-245864D01*
X167450Y-245364D01*
X167323Y-244781D01*
X166880Y-244364D01*
X166436Y-244197D01*
X165866D01*
G01X166436D02*
X166816Y-243947D01*
X167133Y-243531D01*
X167260Y-243031D01*
X167133Y-242531D01*
X166816Y-242114D01*
X166246Y-241864D01*
X165676Y-241947D01*
X165106Y-242281D01*
G01X170016Y-246281D02*
X170460Y-246697D01*
X170966Y-246864D01*
X171473Y-246697D01*
X171916Y-246197D01*
X172233Y-245447D01*
X172360Y-244697D01*
Y-243781D01*
X172233Y-243031D01*
X171916Y-242364D01*
X171536Y-242031D01*
X171093Y-241864D01*
X170586Y-242031D01*
X170206Y-242364D01*
X169953Y-242864D01*
X169826Y-243531D01*
X169953Y-244114D01*
X170270Y-244697D01*
X170650Y-245031D01*
X171093Y-245114D01*
X171600Y-244947D01*
X171980Y-244531D01*
X172360Y-243781D01*
G01X176066Y-246864D02*
X176193Y-245781D01*
X176383Y-244864D01*
X176636Y-244031D01*
X176953Y-243114D01*
X177460Y-241864D01*
X174926D01*
G01X180470Y-245197D02*
X182116D01*
G01X185000Y-245864D02*
X185380Y-246447D01*
X185886Y-246781D01*
X186456Y-246864D01*
X186963Y-246781D01*
X187470Y-246364D01*
X187786Y-245864D01*
X187850Y-245364D01*
X187723Y-244781D01*
X187280Y-244364D01*
X186836Y-244197D01*
X186266D01*
G01X186836D02*
X187216Y-243947D01*
X187533Y-243531D01*
X187660Y-243031D01*
X187533Y-242531D01*
X187216Y-242114D01*
X186646Y-241864D01*
X186076Y-241947D01*
X185506Y-242281D01*
G01X190290Y-244781D02*
X190733Y-244197D01*
X191113Y-243864D01*
X191620Y-243697D01*
X192063Y-243864D01*
X192380Y-244197D01*
X192633Y-244697D01*
X192696Y-245281D01*
X192633Y-245781D01*
X192380Y-246281D01*
X192000Y-246697D01*
X191556Y-246864D01*
X191050Y-246697D01*
X190606Y-246197D01*
X190353Y-245447D01*
X190290Y-244614D01*
X190416Y-243531D01*
X190606Y-242947D01*
X190923Y-242364D01*
X191366Y-241947D01*
X191810Y-241864D01*
X192253Y-242031D01*
X192570Y-242447D01*
G01X196593Y-246864D02*
Y-241864D01*
X195833Y-242864D01*
G01Y-246864D02*
X197353D01*
G01X202453D02*
Y-241864D01*
X200110Y-245447D01*
X203276D01*
G01X26493Y-176864D02*
Y-251864D01*
X526493D01*
Y-176864D01*
X26493D01*
G01X221493D02*
Y-251864D01*
G01Y-226864D02*
X324493D01*
Y-201864D01*
G01X221493D02*
X324493D01*
G01X332000Y-236864D02*
Y-231864D01*
X333266D01*
X333773Y-232114D01*
X334153Y-232447D01*
X334470Y-232947D01*
X334723Y-233531D01*
X334786Y-234364D01*
X334723Y-235197D01*
X334470Y-235781D01*
X334153Y-236281D01*
X333773Y-236614D01*
X333266Y-236864D01*
X332000D01*
G01X336910D02*
X338493Y-231864D01*
X340076Y-236864D01*
G01X339506Y-235114D02*
X337480D01*
G01X343593Y-231864D02*
Y-236864D01*
G01X342136Y-231864D02*
X345050D01*
G01X349960Y-236864D02*
X347426D01*
Y-231864D01*
X349960D01*
G01X348946Y-234281D02*
X347426D01*
G01X353793Y-237031D02*
X353666Y-236947D01*
Y-236781D01*
X353793Y-236697D01*
X353920Y-236781D01*
Y-236947D01*
X353793Y-237031D01*
G01Y-234781D02*
X353666Y-234697D01*
Y-234531D01*
X353793Y-234447D01*
X353920Y-234531D01*
Y-234697D01*
X353793Y-234781D01*
G01X326493Y-176864D02*
Y-251864D01*
G01X324493Y-176864D02*
Y-251864D01*
G01X326493Y-226864D02*
X526493D01*
G01X332126Y-211864D02*
Y-206864D01*
X333646D01*
X334153Y-207114D01*
X334533Y-207697D01*
X334660Y-208364D01*
X334533Y-209031D01*
X334216Y-209531D01*
X333646Y-209781D01*
X332126D01*
G01X337353Y-212031D02*
X339633Y-206864D01*
G01X342136Y-211864D02*
Y-206864D01*
X345050Y-211864D01*
Y-206864D01*
G01X348693Y-212031D02*
X348566Y-211947D01*
Y-211781D01*
X348693Y-211697D01*
X348820Y-211781D01*
Y-211947D01*
X348693Y-212031D01*
G01Y-209781D02*
X348566Y-209697D01*
Y-209531D01*
X348693Y-209447D01*
X348820Y-209531D01*
Y-209697D01*
X348693Y-209781D01*
G01X326493Y-201864D02*
X526493D01*
G01X332126Y-186864D02*
Y-181864D01*
X333646D01*
X334153Y-182114D01*
X334533Y-182697D01*
X334660Y-183364D01*
X334533Y-184031D01*
X334216Y-184531D01*
X333646Y-184781D01*
X332126D01*
G01X337226Y-186864D02*
Y-181864D01*
X338810D01*
X339316Y-182114D01*
X339633Y-182447D01*
X339760Y-183114D01*
X339633Y-183781D01*
X339253Y-184197D01*
X338810Y-184447D01*
X337226D01*
G01X338810D02*
X339760Y-186864D01*
G01X343593D02*
X343086Y-186781D01*
X342643Y-186447D01*
X342263Y-185947D01*
X342010Y-185364D01*
X341883Y-184697D01*
Y-184031D01*
X342010Y-183364D01*
X342263Y-182781D01*
X342643Y-182281D01*
X343086Y-181947D01*
X343593Y-181864D01*
X344100Y-181947D01*
X344543Y-182281D01*
X344923Y-182781D01*
X345176Y-183364D01*
X345303Y-184031D01*
Y-184697D01*
X345176Y-185364D01*
X344923Y-185947D01*
X344543Y-186447D01*
X344100Y-186781D01*
X343593Y-186864D01*
G01X347426Y-185864D02*
X347743Y-186364D01*
X348123Y-186697D01*
X348566Y-186864D01*
X349073Y-186697D01*
X349453Y-186364D01*
X349833Y-185864D01*
X349960Y-185197D01*
Y-181864D01*
G01X355060Y-186864D02*
X352526D01*
Y-181864D01*
X355060D01*
G01X354046Y-184281D02*
X352526D01*
G01X360286Y-182281D02*
X359906Y-182031D01*
X359463Y-181864D01*
X358956D01*
X358386Y-182114D01*
X357943Y-182531D01*
X357626Y-183031D01*
X357373Y-183864D01*
X357310Y-184614D01*
X357436Y-185364D01*
X357626Y-185864D01*
X358006Y-186364D01*
X358450Y-186697D01*
X358893Y-186864D01*
X359336D01*
X359780Y-186697D01*
X360160Y-186447D01*
X360476Y-186114D01*
G01X363993Y-181864D02*
Y-186864D01*
G01X362536Y-181864D02*
X365450D01*
G01X369093Y-187031D02*
X368966Y-186947D01*
Y-186781D01*
X369093Y-186697D01*
X369220Y-186781D01*
Y-186947D01*
X369093Y-187031D01*
G01Y-184781D02*
X368966Y-184697D01*
Y-184531D01*
X369093Y-184447D01*
X369220Y-184531D01*
Y-184697D01*
X369093Y-184781D01*
G01X447126Y-236864D02*
Y-231864D01*
X448710D01*
X449216Y-232114D01*
X449533Y-232447D01*
X449660Y-233114D01*
X449533Y-233781D01*
X449153Y-234197D01*
X448710Y-234447D01*
X447126D01*
G01X448710D02*
X449660Y-236864D01*
G01X454760D02*
X452226D01*
Y-231864D01*
X454760D01*
G01X453746Y-234281D02*
X452226D01*
G01X457010Y-231864D02*
X458593Y-236864D01*
X460176Y-231864D01*
G01X463693Y-237031D02*
X463566Y-236947D01*
Y-236781D01*
X463693Y-236697D01*
X463820Y-236781D01*
Y-236947D01*
X463693Y-237031D01*
G01Y-234781D02*
X463566Y-234697D01*
Y-234531D01*
X463693Y-234447D01*
X463820Y-234531D01*
Y-234697D01*
X463693Y-234781D01*
G01X441493Y-226864D02*
Y-251864D01*
G01X490493Y-226864D02*
Y-251864D01*
G01X-1043962Y-705877D02*
Y2342823D01*
X2300638D01*
Y-705877D01*
X-1043962D01*
G01X37198Y-238524D02*
X37825Y-239049D01*
X38530Y-239364D01*
X39156D01*
X39783Y-239049D01*
X40253Y-238524D01*
X40488Y-237789D01*
X40331Y-237054D01*
X39940Y-236424D01*
X39235Y-236004D01*
X38295Y-235794D01*
X37746Y-235374D01*
X37511Y-234639D01*
X37668Y-233904D01*
X38060Y-233379D01*
X38608Y-233064D01*
X39156D01*
X39705Y-233274D01*
X40175Y-233799D01*
G01X43498Y-239364D02*
Y-233064D01*
G01X46788D02*
Y-239364D01*
G01Y-236214D02*
X43498D01*
G01X50503Y-233064D02*
X52383D01*
G01X51443D02*
Y-239364D01*
G01X50503D02*
X52383D01*
G01X59310D02*
X56176D01*
Y-233064D01*
X59310D01*
G01X58056Y-236109D02*
X56176D01*
G01X62241Y-239364D02*
Y-233064D01*
X65845Y-239364D01*
Y-233064D01*
G01X70186Y-240519D02*
X70500Y-239154D01*
G01X76643Y-233064D02*
Y-239364D01*
G01X74841Y-233064D02*
X78445D01*
G01X80985Y-239364D02*
X82943Y-233064D01*
X84901Y-239364D01*
G01X84196Y-237159D02*
X81690D01*
G01X88303Y-233064D02*
X90183D01*
G01X89243D02*
Y-239364D01*
G01X88303D02*
X90183D01*
G01X93193Y-233064D02*
X94290Y-239364D01*
X95543Y-233064D01*
X96796Y-239364D01*
X97893Y-233064D01*
G01X99885Y-239364D02*
X101843Y-233064D01*
X103801Y-239364D01*
G01X103096Y-237159D02*
X100590D01*
G01X106341Y-239364D02*
Y-233064D01*
X109945Y-239364D01*
Y-233064D01*
G01X119176Y-239364D02*
Y-233064D01*
X121135D01*
X121761Y-233379D01*
X122153Y-233799D01*
X122310Y-234639D01*
X122153Y-235479D01*
X121683Y-236004D01*
X121135Y-236319D01*
X119176D01*
G01X121135D02*
X122310Y-239364D01*
G01X127043Y-239574D02*
X126886Y-239469D01*
Y-239259D01*
X127043Y-239154D01*
X127200Y-239259D01*
Y-239469D01*
X127043Y-239574D01*
G01X133343Y-239364D02*
X132716Y-239259D01*
X132168Y-238839D01*
X131698Y-238209D01*
X131385Y-237474D01*
X131228Y-236634D01*
Y-235794D01*
X131385Y-234954D01*
X131698Y-234219D01*
X132168Y-233589D01*
X132716Y-233169D01*
X133343Y-233064D01*
X133970Y-233169D01*
X134518Y-233589D01*
X134988Y-234219D01*
X135301Y-234954D01*
X135458Y-235794D01*
Y-236634D01*
X135301Y-237474D01*
X134988Y-238209D01*
X134518Y-238839D01*
X133970Y-239259D01*
X133343Y-239364D01*
G01X139643Y-239574D02*
X139486Y-239469D01*
Y-239259D01*
X139643Y-239154D01*
X139800Y-239259D01*
Y-239469D01*
X139643Y-239574D01*
G01X147666Y-233589D02*
X147196Y-233274D01*
X146648Y-233064D01*
X146021D01*
X145316Y-233379D01*
X144768Y-233904D01*
X144376Y-234534D01*
X144063Y-235584D01*
X143985Y-236529D01*
X144141Y-237474D01*
X144376Y-238104D01*
X144846Y-238734D01*
X145395Y-239154D01*
X145943Y-239364D01*
X146491D01*
X147040Y-239154D01*
X147510Y-238839D01*
X147901Y-238419D01*
G01X152243Y-239574D02*
X152086Y-239469D01*
Y-239259D01*
X152243Y-239154D01*
X152400Y-239259D01*
Y-239469D01*
X152243Y-239574D01*
G01X37120Y-229364D02*
Y-223064D01*
G01X40096D02*
X37120Y-226949D01*
G01X40566Y-229364D02*
X38451Y-225164D01*
G01X43420Y-223064D02*
Y-227579D01*
X43733Y-228524D01*
X44360Y-229154D01*
X45143Y-229364D01*
X45926Y-229154D01*
X46553Y-228524D01*
X46866Y-227579D01*
Y-223064D01*
G01X53010Y-229364D02*
X49876D01*
Y-223064D01*
X53010D01*
G01X51756Y-226109D02*
X49876D01*
G01X56803Y-223064D02*
X58683D01*
G01X57743D02*
Y-229364D01*
G01X56803D02*
X58683D01*
G01X68698Y-228524D02*
X69325Y-229049D01*
X70030Y-229364D01*
X70656D01*
X71283Y-229049D01*
X71753Y-228524D01*
X71988Y-227789D01*
X71831Y-227054D01*
X71440Y-226424D01*
X70735Y-226004D01*
X69795Y-225794D01*
X69246Y-225374D01*
X69011Y-224639D01*
X69168Y-223904D01*
X69560Y-223379D01*
X70108Y-223064D01*
X70656D01*
X71205Y-223274D01*
X71675Y-223799D01*
G01X74998Y-229364D02*
Y-223064D01*
G01X78288D02*
Y-229364D01*
G01Y-226214D02*
X74998D01*
G01X80985Y-229364D02*
X82943Y-223064D01*
X84901Y-229364D01*
G01X84196Y-227159D02*
X81690D01*
G01X87441Y-229364D02*
Y-223064D01*
X91045Y-229364D01*
Y-223064D01*
G01X100198Y-229364D02*
Y-223064D01*
G01X103488D02*
Y-229364D01*
G01Y-226214D02*
X100198D01*
G01X106498Y-228524D02*
X107125Y-229049D01*
X107830Y-229364D01*
X108456D01*
X109083Y-229049D01*
X109553Y-228524D01*
X109788Y-227789D01*
X109631Y-227054D01*
X109240Y-226424D01*
X108535Y-226004D01*
X107595Y-225794D01*
X107046Y-225374D01*
X106811Y-224639D01*
X106968Y-223904D01*
X107360Y-223379D01*
X107908Y-223064D01*
X108456D01*
X109005Y-223274D01*
X109475Y-223799D01*
G01X113503Y-223064D02*
X115383D01*
G01X114443D02*
Y-229364D01*
G01X113503D02*
X115383D01*
G01X118785D02*
X120743Y-223064D01*
X122701Y-229364D01*
G01X121996Y-227159D02*
X119490D01*
G01X125241Y-229364D02*
Y-223064D01*
X128845Y-229364D01*
Y-223064D01*
G01X133813Y-226214D02*
X135380D01*
Y-228104D01*
X134910Y-228734D01*
X134361Y-229154D01*
X133578Y-229364D01*
X132795Y-229154D01*
X132246Y-228734D01*
X131776Y-228104D01*
X131463Y-227369D01*
X131306Y-226529D01*
Y-225794D01*
X131463Y-225164D01*
X131776Y-224429D01*
X132246Y-223799D01*
X132716Y-223379D01*
X133343Y-223064D01*
X133891D01*
X134518Y-223274D01*
X134988Y-223694D01*
G01X139486Y-230519D02*
X139800Y-229154D01*
G01X145943Y-223064D02*
Y-229364D01*
G01X144141Y-223064D02*
X147745D01*
G01X150285Y-229364D02*
X152243Y-223064D01*
X154201Y-229364D01*
G01X153496Y-227159D02*
X150990D01*
G01X158543Y-229364D02*
X157916Y-229259D01*
X157368Y-228839D01*
X156898Y-228209D01*
X156585Y-227474D01*
X156428Y-226634D01*
Y-225794D01*
X156585Y-224954D01*
X156898Y-224219D01*
X157368Y-223589D01*
X157916Y-223169D01*
X158543Y-223064D01*
X159170Y-223169D01*
X159718Y-223589D01*
X160188Y-224219D01*
X160501Y-224954D01*
X160658Y-225794D01*
Y-226634D01*
X160501Y-227474D01*
X160188Y-228209D01*
X159718Y-228839D01*
X159170Y-229259D01*
X158543Y-229364D01*
G01X171143D02*
Y-226529D01*
X169576Y-223064D01*
G01X172710D02*
X171143Y-226529D01*
G01X175720Y-223064D02*
Y-227579D01*
X176033Y-228524D01*
X176660Y-229154D01*
X177443Y-229364D01*
X178226Y-229154D01*
X178853Y-228524D01*
X179166Y-227579D01*
Y-223064D01*
G01X181785Y-229364D02*
X183743Y-223064D01*
X185701Y-229364D01*
G01X184996Y-227159D02*
X182490D01*
G01X188241Y-229364D02*
Y-223064D01*
X191845Y-229364D01*
Y-223064D01*
G01X37041Y-219364D02*
Y-213064D01*
X40645Y-219364D01*
Y-213064D01*
G01X45143Y-219364D02*
X44516Y-219259D01*
X43968Y-218839D01*
X43498Y-218209D01*
X43185Y-217474D01*
X43028Y-216634D01*
Y-215794D01*
X43185Y-214954D01*
X43498Y-214219D01*
X43968Y-213589D01*
X44516Y-213169D01*
X45143Y-213064D01*
X45770Y-213169D01*
X46318Y-213589D01*
X46788Y-214219D01*
X47101Y-214954D01*
X47258Y-215794D01*
Y-216634D01*
X47101Y-217474D01*
X46788Y-218209D01*
X46318Y-218839D01*
X45770Y-219259D01*
X45143Y-219364D01*
G01X51443Y-219574D02*
X51286Y-219469D01*
Y-219259D01*
X51443Y-219154D01*
X51600Y-219259D01*
Y-219469D01*
X51443Y-219574D01*
G01X57743Y-219364D02*
Y-213064D01*
X56803Y-214324D01*
G01Y-219364D02*
X58683D01*
G01X64043D02*
X64591Y-219259D01*
X65218Y-218944D01*
X65610Y-218419D01*
X65766Y-217684D01*
X65610Y-216949D01*
X65140Y-216319D01*
X64435Y-216004D01*
X63651D01*
X63181Y-215794D01*
X62790Y-215269D01*
X62633Y-214534D01*
X62868Y-213799D01*
X63416Y-213274D01*
X64043Y-213064D01*
X64670Y-213274D01*
X65218Y-213799D01*
X65453Y-214534D01*
X65296Y-215269D01*
X64905Y-215794D01*
X64435Y-216004D01*
X63651D01*
X62946Y-216319D01*
X62476Y-216949D01*
X62320Y-217684D01*
X62476Y-218419D01*
X62868Y-218944D01*
X63495Y-219259D01*
X64043Y-219364D01*
G01X70343D02*
X70891Y-219259D01*
X71518Y-218944D01*
X71910Y-218419D01*
X72066Y-217684D01*
X71910Y-216949D01*
X71440Y-216319D01*
X70735Y-216004D01*
X69951D01*
X69481Y-215794D01*
X69090Y-215269D01*
X68933Y-214534D01*
X69168Y-213799D01*
X69716Y-213274D01*
X70343Y-213064D01*
X70970Y-213274D01*
X71518Y-213799D01*
X71753Y-214534D01*
X71596Y-215269D01*
X71205Y-215794D01*
X70735Y-216004D01*
X69951D01*
X69246Y-216319D01*
X68776Y-216949D01*
X68620Y-217684D01*
X68776Y-218419D01*
X69168Y-218944D01*
X69795Y-219259D01*
X70343Y-219364D01*
G01X76486Y-220519D02*
X76800Y-219154D01*
G01X80593Y-213064D02*
X81690Y-219364D01*
X82943Y-213064D01*
X84196Y-219364D01*
X85293Y-213064D01*
G01X90810Y-219364D02*
X87676D01*
Y-213064D01*
X90810D01*
G01X89556Y-216109D02*
X87676D01*
G01X93741Y-219364D02*
Y-213064D01*
X97345Y-219364D01*
Y-213064D01*
G01X106498Y-219364D02*
Y-213064D01*
G01X109788D02*
Y-219364D01*
G01Y-216214D02*
X106498D01*
G01X112093Y-213064D02*
X113190Y-219364D01*
X114443Y-213064D01*
X115696Y-219364D01*
X116793Y-213064D01*
G01X118785Y-219364D02*
X120743Y-213064D01*
X122701Y-219364D01*
G01X121996Y-217159D02*
X119490D01*
G01X131855Y-214114D02*
X132325Y-213484D01*
X132873Y-213169D01*
X133500Y-213064D01*
X134283Y-213274D01*
X134831Y-213799D01*
X134988Y-214429D01*
X134910Y-215059D01*
X134596Y-215584D01*
X133030Y-216634D01*
X132325Y-217369D01*
X131855Y-218419D01*
X131698Y-219364D01*
X134988D01*
G01X137841D02*
Y-213064D01*
X141445Y-219364D01*
Y-213064D01*
G01X144220Y-219364D02*
Y-213064D01*
X145786D01*
X146413Y-213379D01*
X146883Y-213799D01*
X147275Y-214429D01*
X147588Y-215164D01*
X147666Y-216214D01*
X147588Y-217264D01*
X147275Y-217999D01*
X146883Y-218629D01*
X146413Y-219049D01*
X145786Y-219364D01*
X144220D01*
G01X156976D02*
Y-213064D01*
X158935D01*
X159561Y-213379D01*
X159953Y-213799D01*
X160110Y-214639D01*
X159953Y-215479D01*
X159483Y-216004D01*
X158935Y-216319D01*
X156976D01*
G01X158935D02*
X160110Y-219364D01*
G01X163120D02*
Y-213064D01*
X164686D01*
X165313Y-213379D01*
X165783Y-213799D01*
X166175Y-214429D01*
X166488Y-215164D01*
X166566Y-216214D01*
X166488Y-217264D01*
X166175Y-217999D01*
X165783Y-218629D01*
X165313Y-219049D01*
X164686Y-219364D01*
X163120D01*
G01X171143Y-219574D02*
X170986Y-219469D01*
Y-219259D01*
X171143Y-219154D01*
X171300Y-219259D01*
Y-219469D01*
X171143Y-219574D01*
G01X61143Y-206664D02*
X58623Y-206247D01*
X56418Y-204581D01*
X54528Y-202081D01*
X53268Y-199164D01*
X52638Y-195831D01*
Y-192497D01*
X53268Y-189164D01*
X54528Y-186247D01*
X56418Y-183748D01*
X58623Y-182081D01*
X61143Y-181664D01*
X63663Y-182081D01*
X65868Y-183748D01*
X67758Y-186247D01*
X69018Y-189164D01*
X69648Y-192497D01*
Y-195831D01*
X69018Y-199164D01*
X67758Y-202081D01*
X65868Y-204581D01*
X63663Y-206247D01*
X61143Y-206664D01*
G01X63663Y-199997D02*
X67443Y-206664D01*
G01X80988Y-189998D02*
Y-201664D01*
X82248Y-204581D01*
X84138Y-206247D01*
X86343Y-206664D01*
X88548Y-206247D01*
X90438Y-204581D01*
X91698Y-201664D01*
G01Y-206664D02*
Y-189998D01*
G01X117213Y-206664D02*
Y-189998D01*
G01Y-192914D02*
X115953Y-191248D01*
X114063Y-190414D01*
X111858Y-189998D01*
X109653Y-190831D01*
X107763Y-192497D01*
X106503Y-194998D01*
X105873Y-198331D01*
X106503Y-201664D01*
X107763Y-204165D01*
X109653Y-205831D01*
X111858Y-206664D01*
X114063Y-206247D01*
X115953Y-204998D01*
X117213Y-203331D01*
G01X131388Y-206664D02*
Y-189998D01*
G01Y-194164D02*
X132648Y-192081D01*
X134538Y-190414D01*
X137058Y-189998D01*
X139263Y-190414D01*
X141153Y-192081D01*
X142098Y-194998D01*
Y-206664D01*
G01X161943Y-181664D02*
Y-206664D01*
G01X157533Y-189998D02*
X166353D01*
G01X192813Y-206664D02*
Y-189998D01*
G01Y-192914D02*
X191553Y-191248D01*
X189663Y-190414D01*
X187458Y-189998D01*
X185253Y-190831D01*
X183363Y-192497D01*
X182103Y-194998D01*
X181473Y-198331D01*
X182103Y-201664D01*
X183363Y-204165D01*
X185253Y-205831D01*
X187458Y-206664D01*
X189663Y-206247D01*
X191553Y-204998D01*
X192813Y-203331D01*
G01X232493Y-186364D02*
Y-194364D01*
X236493D01*
G01X244293D02*
Y-189031D01*
G01Y-189964D02*
X243893Y-189431D01*
X243293Y-189164D01*
X242593Y-189031D01*
X241893Y-189297D01*
X241293Y-189831D01*
X240893Y-190631D01*
X240693Y-191697D01*
X240893Y-192764D01*
X241293Y-193564D01*
X241893Y-194097D01*
X242593Y-194364D01*
X243293Y-194231D01*
X243893Y-193831D01*
X244293Y-193298D01*
G01X248393Y-196764D02*
X248993Y-197031D01*
X249793Y-196764D01*
X250293Y-196231D01*
X250693Y-195564D01*
X251293Y-193431D01*
X252593Y-189031D01*
G01X249393D02*
X251293Y-193431D01*
G01X256993Y-190764D02*
X260193D01*
X259893Y-189831D01*
X259393Y-189297D01*
X258693Y-189031D01*
X257993Y-189164D01*
X257393Y-189564D01*
X256993Y-190497D01*
X256793Y-191298D01*
Y-192097D01*
X256993Y-192897D01*
X257493Y-193697D01*
X258093Y-194231D01*
X258793Y-194364D01*
X259493Y-194097D01*
X260193Y-193298D01*
G01X265093Y-194364D02*
Y-189031D01*
G01Y-190097D02*
X265593Y-189564D01*
X266093Y-189164D01*
X266793Y-189031D01*
X267293Y-189164D01*
X267893Y-189564D01*
G01X254793Y-236364D02*
X257193D01*
G01X255993D02*
Y-244364D01*
G01X254793D02*
X257193D01*
G01X262593D02*
Y-239031D01*
G01Y-240097D02*
X263093Y-239564D01*
X263593Y-239164D01*
X264293Y-239031D01*
X264793Y-239164D01*
X265393Y-239564D01*
G01X270493Y-240764D02*
X273693D01*
X273393Y-239831D01*
X272893Y-239297D01*
X272193Y-239031D01*
X271493Y-239164D01*
X270893Y-239564D01*
X270493Y-240497D01*
X270293Y-241298D01*
Y-242097D01*
X270493Y-242897D01*
X270993Y-243697D01*
X271593Y-244231D01*
X272293Y-244364D01*
X272993Y-244097D01*
X273693Y-243298D01*
G01X278293Y-244364D02*
Y-239031D01*
G01Y-240364D02*
X278693Y-239697D01*
X279293Y-239164D01*
X280093Y-239031D01*
X280793Y-239164D01*
X281393Y-239697D01*
X281693Y-240631D01*
Y-244364D01*
G01X286493Y-240764D02*
X289693D01*
X289393Y-239831D01*
X288893Y-239297D01*
X288193Y-239031D01*
X287493Y-239164D01*
X286893Y-239564D01*
X286493Y-240497D01*
X286293Y-241298D01*
Y-242097D01*
X286493Y-242897D01*
X286993Y-243697D01*
X287593Y-244231D01*
X288293Y-244364D01*
X288993Y-244097D01*
X289693Y-243298D01*
G01X264793Y-211364D02*
X267193D01*
G01X265993D02*
Y-219364D01*
G01X264793D02*
X267193D01*
G01X271693D02*
Y-211364D01*
X276293Y-219364D01*
Y-211364D01*
G01X279793Y-217764D02*
X280393Y-218697D01*
X281193Y-219231D01*
X282093Y-219364D01*
X282893Y-219231D01*
X283693Y-218564D01*
X284193Y-217764D01*
X284293Y-216964D01*
X284093Y-216031D01*
X283393Y-215364D01*
X282693Y-215097D01*
X281793D01*
G01X282693D02*
X283293Y-214697D01*
X283793Y-214031D01*
X283993Y-213231D01*
X283793Y-212431D01*
X283293Y-211764D01*
X282393Y-211364D01*
X281493Y-211497D01*
X280593Y-212031D01*
G01X285993Y-194364D02*
X286693Y-194231D01*
X287493Y-193831D01*
X287993Y-193164D01*
X288193Y-192231D01*
X287993Y-191298D01*
X287393Y-190497D01*
X286493Y-190097D01*
X285493D01*
X284893Y-189831D01*
X284393Y-189164D01*
X284193Y-188231D01*
X284493Y-187297D01*
X285193Y-186631D01*
X285993Y-186364D01*
X286793Y-186631D01*
X287493Y-187297D01*
X287793Y-188231D01*
X287593Y-189164D01*
X287093Y-189831D01*
X286493Y-190097D01*
X285493D01*
X284593Y-190497D01*
X283993Y-191298D01*
X283793Y-192231D01*
X283993Y-193164D01*
X284493Y-193831D01*
X285293Y-194231D01*
X285993Y-194364D01*
G01X359093Y-237697D02*
X359693Y-236897D01*
X360393Y-236497D01*
X361193Y-236364D01*
X362193Y-236631D01*
X362893Y-237297D01*
X363093Y-238097D01*
X362993Y-238898D01*
X362593Y-239564D01*
X360593Y-240897D01*
X359693Y-241831D01*
X359093Y-243164D01*
X358893Y-244364D01*
X363093D01*
G01X368993Y-236364D02*
X368193Y-236631D01*
X367593Y-237297D01*
X367193Y-238097D01*
X366893Y-239164D01*
X366793Y-240364D01*
X366893Y-241564D01*
X367193Y-242631D01*
X367593Y-243431D01*
X368193Y-244097D01*
X368993Y-244364D01*
X369793Y-244097D01*
X370393Y-243431D01*
X370793Y-242631D01*
X371093Y-241564D01*
X371193Y-240364D01*
X371093Y-239164D01*
X370793Y-238097D01*
X370393Y-237297D01*
X369793Y-236631D01*
X368993Y-236364D01*
G01X376993Y-244364D02*
Y-236364D01*
X375793Y-237964D01*
G01Y-244364D02*
X378193D01*
G01X383093Y-237697D02*
X383693Y-236897D01*
X384393Y-236497D01*
X385193Y-236364D01*
X386193Y-236631D01*
X386893Y-237297D01*
X387093Y-238097D01*
X386993Y-238898D01*
X386593Y-239564D01*
X384593Y-240897D01*
X383693Y-241831D01*
X383093Y-243164D01*
X382893Y-244364D01*
X387093D01*
G01X391193Y-244631D02*
X394793Y-236364D01*
G01X400993Y-244364D02*
Y-236364D01*
X399793Y-237964D01*
G01Y-244364D02*
X402193D01*
G01X408993Y-236364D02*
X408193Y-236631D01*
X407593Y-237297D01*
X407193Y-238097D01*
X406893Y-239164D01*
X406793Y-240364D01*
X406893Y-241564D01*
X407193Y-242631D01*
X407593Y-243431D01*
X408193Y-244097D01*
X408993Y-244364D01*
X409793Y-244097D01*
X410393Y-243431D01*
X410793Y-242631D01*
X411093Y-241564D01*
X411193Y-240364D01*
X411093Y-239164D01*
X410793Y-238097D01*
X410393Y-237297D01*
X409793Y-236631D01*
X408993Y-236364D01*
G01X415193Y-244631D02*
X418793Y-236364D01*
G01X422793Y-242764D02*
X423393Y-243697D01*
X424193Y-244231D01*
X425093Y-244364D01*
X425893Y-244231D01*
X426693Y-243564D01*
X427193Y-242764D01*
X427293Y-241964D01*
X427093Y-241031D01*
X426393Y-240364D01*
X425693Y-240097D01*
X424793D01*
G01X425693D02*
X426293Y-239697D01*
X426793Y-239031D01*
X426993Y-238231D01*
X426793Y-237431D01*
X426293Y-236764D01*
X425393Y-236364D01*
X424493Y-236497D01*
X423593Y-237031D01*
G01X432993Y-244364D02*
Y-236364D01*
X431793Y-237964D01*
G01Y-244364D02*
X434193D01*
G01X358793Y-219364D02*
Y-211364D01*
X360793D01*
X361593Y-211764D01*
X362193Y-212297D01*
X362693Y-213097D01*
X363093Y-214031D01*
X363193Y-215364D01*
X363093Y-216697D01*
X362693Y-217631D01*
X362193Y-218431D01*
X361593Y-218964D01*
X360793Y-219364D01*
X358793D01*
G01X366493D02*
X368993Y-211364D01*
X371493Y-219364D01*
G01X370593Y-216564D02*
X367393D01*
G01X376993Y-211364D02*
Y-219364D01*
G01X374693Y-211364D02*
X379293D01*
G01X383093Y-216031D02*
X383793Y-215097D01*
X384393Y-214564D01*
X385193Y-214297D01*
X385893Y-214564D01*
X386393Y-215097D01*
X386793Y-215897D01*
X386893Y-216831D01*
X386793Y-217631D01*
X386393Y-218431D01*
X385793Y-219097D01*
X385093Y-219364D01*
X384293Y-219097D01*
X383593Y-218298D01*
X383193Y-217097D01*
X383093Y-215764D01*
X383293Y-214031D01*
X383593Y-213097D01*
X384093Y-212164D01*
X384793Y-211497D01*
X385493Y-211364D01*
X386193Y-211631D01*
X386693Y-212297D01*
G01X390393Y-219364D02*
Y-211364D01*
X392993Y-218031D01*
X395593Y-211364D01*
Y-219364D01*
G01X400993Y-211364D02*
Y-219364D01*
G01X398693Y-211364D02*
X403293D01*
G01X406893Y-219364D02*
Y-211364D01*
G01X411093D02*
Y-219364D01*
G01Y-215364D02*
X406893D01*
G01X414793Y-217764D02*
X415393Y-218697D01*
X416193Y-219231D01*
X417093Y-219364D01*
X417893Y-219231D01*
X418693Y-218564D01*
X419193Y-217764D01*
X419293Y-216964D01*
X419093Y-216031D01*
X418393Y-215364D01*
X417693Y-215097D01*
X416793D01*
G01X417693D02*
X418293Y-214697D01*
X418793Y-214031D01*
X418993Y-213231D01*
X418793Y-212431D01*
X418293Y-211764D01*
X417393Y-211364D01*
X416493Y-211497D01*
X415593Y-212031D01*
G01X422493Y-219364D02*
X424993Y-211364D01*
X427493Y-219364D01*
G01X426593Y-216564D02*
X423393D01*
G01X430793Y-219364D02*
Y-211364D01*
X432793D01*
X433593Y-211764D01*
X434193Y-212297D01*
X434693Y-213097D01*
X435093Y-214031D01*
X435193Y-215364D01*
X435093Y-216697D01*
X434693Y-217631D01*
X434193Y-218431D01*
X433593Y-218964D01*
X432793Y-219364D01*
X430793D01*
G01X440993Y-211364D02*
X440193Y-211631D01*
X439593Y-212297D01*
X439193Y-213097D01*
X438893Y-214164D01*
X438793Y-215364D01*
X438893Y-216564D01*
X439193Y-217631D01*
X439593Y-218431D01*
X440193Y-219097D01*
X440993Y-219364D01*
X441793Y-219097D01*
X442393Y-218431D01*
X442793Y-217631D01*
X443093Y-216564D01*
X443193Y-215364D01*
X443093Y-214164D01*
X442793Y-213097D01*
X442393Y-212297D01*
X441793Y-211631D01*
X440993Y-211364D01*
G01X380993Y-186364D02*
Y-194364D01*
G01X378693Y-186364D02*
X383293D01*
G01X387093Y-191031D02*
X387793Y-190097D01*
X388393Y-189564D01*
X389193Y-189297D01*
X389893Y-189564D01*
X390393Y-190097D01*
X390793Y-190897D01*
X390893Y-191831D01*
X390793Y-192631D01*
X390393Y-193431D01*
X389793Y-194097D01*
X389093Y-194364D01*
X388293Y-194097D01*
X387593Y-193298D01*
X387193Y-192097D01*
X387093Y-190764D01*
X387293Y-189031D01*
X387593Y-188097D01*
X388093Y-187164D01*
X388793Y-186497D01*
X389493Y-186364D01*
X390193Y-186631D01*
X390693Y-187297D01*
G01X394393Y-194364D02*
Y-186364D01*
X396993Y-193031D01*
X399593Y-186364D01*
Y-194364D01*
G01X401993Y-197031D02*
X407993D01*
G01X415193Y-187031D02*
X414593Y-186631D01*
X413893Y-186364D01*
X413093D01*
X412193Y-186764D01*
X411493Y-187431D01*
X410993Y-188231D01*
X410593Y-189564D01*
X410493Y-190764D01*
X410693Y-191964D01*
X410993Y-192764D01*
X411593Y-193564D01*
X412293Y-194097D01*
X412993Y-194364D01*
X413693D01*
X414393Y-194097D01*
X414993Y-193697D01*
X415493Y-193164D01*
G01X418393Y-194364D02*
Y-186364D01*
X420993Y-193031D01*
X423593Y-186364D01*
Y-194364D01*
G01X425993Y-197031D02*
X431993D01*
G01X434793Y-194364D02*
Y-186364D01*
X436793D01*
X437593Y-186764D01*
X438193Y-187297D01*
X438693Y-188097D01*
X439093Y-189031D01*
X439193Y-190364D01*
X439093Y-191697D01*
X438693Y-192631D01*
X438193Y-193431D01*
X437593Y-193964D01*
X436793Y-194364D01*
X434793D01*
G01X473793Y-244364D02*
Y-236364D01*
X475793D01*
X476593Y-236764D01*
X477193Y-237297D01*
X477693Y-238097D01*
X478093Y-239031D01*
X478193Y-240364D01*
X478093Y-241697D01*
X477693Y-242631D01*
X477193Y-243431D01*
X476593Y-243964D01*
X475793Y-244364D01*
X473793D01*
G01X503493D02*
Y-236364D01*
X502293Y-237964D01*
G01Y-244364D02*
X504693D01*
G01X509593Y-241031D02*
X510293Y-240097D01*
X510893Y-239564D01*
X511693Y-239297D01*
X512393Y-239564D01*
X512893Y-240097D01*
X513293Y-240897D01*
X513393Y-241831D01*
X513293Y-242631D01*
X512893Y-243431D01*
X512293Y-244097D01*
X511593Y-244364D01*
X510793Y-244097D01*
X510093Y-243298D01*
X509693Y-242097D01*
X509593Y-240764D01*
X509793Y-239031D01*
X510093Y-238097D01*
X510593Y-237164D01*
X511293Y-236497D01*
X511993Y-236364D01*
X512693Y-236631D01*
X513193Y-237297D01*
G54D13*
X155400Y533436D03*
X154246Y527468D03*
X154945Y539233D03*
X159185Y547103D03*
X154900Y548682D03*
X159186Y553402D03*
X157611Y557468D03*
X154410Y557990D03*
X178085Y518755D03*
X178094Y531365D03*
X174720Y531356D03*
X174105Y542290D03*
X167027Y539526D03*
Y536376D03*
X181232Y537654D03*
X207309Y539953D03*
X216184Y268587D03*
X214118Y528583D03*
X236776Y512040D03*
Y534087D03*
X233626Y527788D03*
X230476Y534087D03*
X236776Y527788D03*
Y524639D03*
X233626Y534087D03*
Y543536D03*
X239925Y540386D03*
Y543536D03*
X230476Y537236D03*
Y543536D03*
X236776D03*
X233626Y537236D03*
X243075Y559284D03*
X255673Y512040D03*
X252524D03*
Y549835D03*
X255673D03*
X268272Y512040D03*
X271422D03*
X268272Y549836D03*
X271421D03*
X287173Y499445D03*
X277712Y502595D03*
X277725Y534092D03*
Y527792D03*
Y540391D03*
Y543541D03*
Y537241D03*
X683112Y483723D03*
X683113Y471941D03*
X698683Y487517D03*
X690986Y487660D03*
X687049D03*
X706734Y471913D03*
Y483723D03*
Y475850D03*
G54D23*
G01X-36392Y727917D02*
Y726374D01*
X-42970Y689043D01*
X-38644Y664559D01*
X-48710Y607021D01*
X-46668Y595551D01*
X-44660Y584281D01*
X-50880Y548712D01*
X-42570Y501623D01*
X-51995Y448310D01*
X-53380Y440473D01*
X-51001Y426980D01*
X-45340Y394863D01*
X-52500Y354192D01*
X-48870Y333698D01*
Y332033D01*
G01X-47720D02*
Y333800D01*
X-51332Y354193D01*
X-44172Y394863D01*
X-49833Y426980D01*
X-52212Y440473D01*
X-50827Y448310D01*
X-41402Y501623D01*
X-49712Y548713D01*
X-43492Y584283D01*
X-47542Y607023D01*
X-37476Y664560D01*
X-41802Y689043D01*
X-35242Y726273D01*
Y727999D01*
G01X129650Y250414D02*
X131575Y252339D01*
X133225D01*
X134827Y253628D01*
X135070Y256498D01*
X134390Y258482D01*
X131480Y259869D01*
X127840Y260820D01*
X119518Y265067D01*
X114288Y273250D01*
X101311Y312913D01*
X63196Y358848D01*
X61280Y370642D01*
X57539Y393737D01*
X56690Y395886D01*
X51390Y401972D01*
X47730Y403802D01*
X43470Y403989D01*
X37415Y410245D01*
X33786Y421847D01*
X34120Y436466D01*
Y472804D01*
X33412Y518034D01*
X40820Y531450D01*
X46180Y536292D01*
X55409Y546174D01*
X65930Y549018D01*
Y549022D01*
X72186Y551982D01*
X84442Y553366D01*
X86570Y555146D01*
X127980Y601082D01*
X154300Y606773D01*
X162670Y608897D01*
X177410Y609446D01*
X195780Y608966D01*
X200781Y606060D01*
X203524D01*
X204024Y605560D01*
Y604135D01*
G01X129650Y255414D02*
X131575Y253489D01*
X132819D01*
X133722Y254216D01*
X133903Y256354D01*
X133458Y257651D01*
X131083Y258783D01*
X127428Y259739D01*
X118716Y264184D01*
X113240Y272754D01*
X100286Y312347D01*
X62110Y358354D01*
X60144Y370458D01*
X56423Y393430D01*
X55692Y395279D01*
X50672Y401045D01*
X47435Y402663D01*
X42962Y402860D01*
X36398Y409641D01*
X32631Y421684D01*
X32970Y436480D01*
Y472794D01*
X32257Y518322D01*
X39906Y532175D01*
X45373Y537113D01*
X54792Y547199D01*
X65511Y550097D01*
X71867Y553104D01*
X83969Y554470D01*
X85769Y555977D01*
X127374Y602128D01*
X154037Y607893D01*
X162505Y610042D01*
X177404Y610597D01*
X196104Y610108D01*
X201091Y607210D01*
X203524D01*
X204024Y607710D01*
Y609135D01*
G01X219960Y596373D02*
Y597798D01*
X219460Y598298D01*
X205800D01*
X198462Y601048D01*
X195050D01*
X187928Y595989D01*
X165140Y593882D01*
X152040Y593265D01*
X130030Y591483D01*
X97330Y556517D01*
X88760Y549661D01*
X76420Y546781D01*
X72934Y545969D01*
X68190Y542667D01*
X49568Y532312D01*
X44328Y523949D01*
X42760Y443048D01*
X42645Y439601D01*
X40495Y430515D01*
X41974Y420583D01*
Y419433D01*
X41724Y411899D01*
X44742Y408171D01*
X50735Y407462D01*
X62575Y396944D01*
X74092Y355886D01*
X104960Y317943D01*
X110750Y306010D01*
X116116Y286125D01*
X122987Y268174D01*
X132841Y263632D01*
X153331Y265525D01*
X167457Y266164D01*
X171230Y262991D01*
Y259557D01*
X169345Y257672D01*
X168023D01*
X167426Y257164D01*
X167322Y255855D01*
G01X219960Y601373D02*
Y599948D01*
X219460Y599448D01*
X206009D01*
X198671Y602198D01*
X194683D01*
X187514Y597106D01*
X165060Y595030D01*
X151967Y594413D01*
X129493Y592594D01*
X96546Y557364D01*
X88245Y550722D01*
X76159Y547901D01*
X72458Y547039D01*
X67580Y543645D01*
X48750Y533174D01*
X43184Y524290D01*
X41610Y443078D01*
X41499Y439754D01*
X39324Y430565D01*
X40824Y420497D01*
Y419453D01*
X40560Y411509D01*
X44142Y407083D01*
X50241Y406362D01*
X61559Y396308D01*
X73048Y355345D01*
X103983Y317320D01*
X109667Y305605D01*
X115020Y285768D01*
X122080Y267325D01*
X132640Y262458D01*
X153410Y264377D01*
X167060Y264994D01*
X170080Y262455D01*
Y260034D01*
X168868Y258822D01*
X168008D01*
X167594Y259307D01*
X167698Y260617D01*
G01X130324Y272096D02*
Y273521D01*
X130824Y274021D01*
X133334D01*
X135408Y276094D01*
X135830Y281746D01*
X133144Y291143D01*
X132810Y292310D01*
X132037Y294832D01*
X132036Y294835D01*
X131062Y298012D01*
X131340Y330538D01*
X131847Y340767D01*
X141180Y378234D01*
X155810Y394781D01*
X160313Y419916D01*
X165537Y431853D01*
X166100Y440030D01*
X166570Y446771D01*
X170120Y454816D01*
X172810Y457548D01*
X180480Y458558D01*
X188120Y457548D01*
X192583Y453234D01*
X195242Y446909D01*
X198253Y445058D01*
X200884Y444615D01*
X223738Y446829D01*
X246077Y443824D01*
X260312Y448991D01*
X268575Y448344D01*
X287100Y450293D01*
X309260Y447399D01*
X323321Y439779D01*
X328261Y433446D01*
X337020Y431895D01*
X351570Y431892D01*
X370210Y425124D01*
X378370Y424599D01*
X390779Y423810D01*
X393401Y423385D01*
X394523D01*
X398122Y422423D01*
X399182Y422140D01*
X407459Y420442D01*
X415556Y420957D01*
X421845Y420838D01*
X429701Y422917D01*
X451620Y423111D01*
X469623Y424402D01*
X478770Y429943D01*
X479292Y431169D01*
X483841Y439467D01*
X494754Y461671D01*
X495240Y469675D01*
X495827Y471505D01*
X503529Y480818D01*
X503420Y488573D01*
X502320Y498172D01*
X503382Y503666D01*
X506825Y506791D01*
X515280Y507085D01*
X515292Y507094D01*
X515302Y507092D01*
X516935Y506851D01*
X538900Y504458D01*
X540637Y504506D01*
X548150D01*
X554150Y507599D01*
X558750Y512589D01*
X570020Y514748D01*
X576130Y515253D01*
X585670Y519962D01*
X599960Y529270D01*
X609610Y539364D01*
X616450Y543065D01*
X618410Y547102D01*
X618970Y564653D01*
X621440Y579401D01*
X621050Y584055D01*
X615050Y600933D01*
X611630Y604634D01*
X610041Y606353D01*
X609512Y608065D01*
X609600Y610275D01*
X607775Y613033D01*
X605753Y613746D01*
X601743Y613217D01*
X599847Y613093D01*
X592765Y614131D01*
X590705D01*
X588780Y616056D01*
G01X130324Y277096D02*
Y275671D01*
X130824Y275171D01*
X132857D01*
X134292Y276606D01*
X134667Y281627D01*
X134320Y282840D01*
X133697Y283185D01*
X133284Y284628D01*
X133631Y285251D01*
X133218Y286694D01*
X132595Y287039D01*
X132182Y288482D01*
X132529Y289105D01*
X131707Y291983D01*
X131001Y292356D01*
X130559Y293792D01*
X130936Y294496D01*
X130935Y294499D01*
X129910Y297844D01*
X130190Y330571D01*
X130703Y340936D01*
X140132Y378785D01*
X154734Y395302D01*
X159205Y420253D01*
X164403Y432131D01*
X164952Y440110D01*
X165422Y446851D01*
X165518Y447236D01*
X169152Y455473D01*
X172268Y458637D01*
X180480Y459719D01*
X188647Y458639D01*
X193552Y453897D01*
X196160Y447696D01*
X198665Y446155D01*
X200925Y445775D01*
X202300Y445909D01*
X202760Y446470D01*
X204255Y446617D01*
X204816Y446152D01*
X206310Y446298D01*
X206770Y446860D01*
X208265Y447007D01*
X208826Y446542D01*
X210320Y446688D01*
X210780Y447250D01*
X212275Y447397D01*
X212836Y446932D01*
X214330Y447078D01*
X214790Y447640D01*
X216285Y447787D01*
X216846Y447322D01*
X218340Y447468D01*
X218800Y448030D01*
X220295Y448177D01*
X220856Y447712D01*
X223760Y447987D01*
X245950Y445002D01*
X260154Y450158D01*
X268560Y449499D01*
X287114Y451451D01*
X309620Y448512D01*
X324080Y440676D01*
X328897Y434502D01*
X337121Y433046D01*
X351773Y433043D01*
X370448Y426262D01*
X378443Y425747D01*
X390908Y424955D01*
X393494Y424535D01*
X394675D01*
X399446Y423260D01*
X407540Y421600D01*
X415530Y422108D01*
X421706Y421991D01*
X429546Y424066D01*
X451574Y424261D01*
X469264Y425530D01*
X477857Y430735D01*
X478256Y431672D01*
X482820Y439997D01*
X493620Y461971D01*
X494100Y469889D01*
X494799Y472068D01*
X502373Y481225D01*
X502270Y488499D01*
X501157Y498217D01*
X502325Y504261D01*
X506364Y507926D01*
X515450Y508242D01*
X515453Y508241D01*
X515459Y508232D01*
X515469Y508230D01*
X517081Y507992D01*
X530642Y506516D01*
X531290Y507040D01*
X532783Y506877D01*
X533306Y506226D01*
X534798Y506063D01*
X535446Y506586D01*
X536939Y506423D01*
X537462Y505772D01*
X538947Y505610D01*
X540621Y505656D01*
X547871D01*
X553442Y508528D01*
X558161Y513648D01*
X569864Y515890D01*
X575817Y516382D01*
X585099Y520964D01*
X599220Y530162D01*
X608903Y540290D01*
X615576Y543901D01*
X617268Y547384D01*
X617823Y564767D01*
X620281Y579449D01*
X619916Y583810D01*
X614045Y600326D01*
X610785Y603853D01*
X609019Y605764D01*
X608355Y607914D01*
X608436Y609950D01*
X607028Y612076D01*
X605630Y612569D01*
X601856Y612071D01*
X599800Y611937D01*
X592681Y612981D01*
X590705D01*
X588780Y611056D01*
G01X602314Y607641D02*
X600389Y605716D01*
X599399D01*
X597793Y604047D01*
X597900Y600960D01*
X599261Y598712D01*
X606980Y596361D01*
X607536Y595557D01*
X607930Y594989D01*
X608370Y591344D01*
X608210Y586634D01*
X609330Y582653D01*
X612920Y578392D01*
X613700Y567345D01*
X612920Y552373D01*
X611120Y549849D01*
X596660Y542392D01*
X580060Y523271D01*
X573266Y520130D01*
X573265Y520129D01*
X572795Y520124D01*
X572794D01*
X563173Y520024D01*
X544390Y519830D01*
X526659Y517569D01*
X514390Y518586D01*
X509175Y516825D01*
X499485Y509511D01*
X496484Y503274D01*
X497745Y482145D01*
X491477Y476260D01*
X490158Y470372D01*
X489986Y467834D01*
X489599Y463799D01*
X488181Y459854D01*
X481929Y447347D01*
X474913Y435457D01*
X469116Y431805D01*
X463122Y430471D01*
X462960D01*
X453288Y429593D01*
X427700Y430729D01*
X397691Y430154D01*
X389514Y432435D01*
X381282Y435295D01*
X374619Y435028D01*
X356196Y437713D01*
X339833Y437501D01*
X338218Y437577D01*
X338198D01*
X338180Y437597D01*
X329260Y440340D01*
X324578Y445772D01*
X310830Y452466D01*
X287217Y456060D01*
X267596Y453398D01*
X258140Y453999D01*
X244660Y449400D01*
X223680Y452627D01*
X208110Y451982D01*
X199050Y455672D01*
X191447Y462899D01*
X181113Y464210D01*
X169009Y462531D01*
X164941Y458703D01*
X158514Y449935D01*
X157745Y449256D01*
X157295Y448859D01*
X156898Y448508D01*
X156498Y448045D01*
X156153Y447645D01*
X152187Y442948D01*
X150474Y402334D01*
X133641Y384849D01*
X130929Y377283D01*
X124293Y339236D01*
X124867Y303908D01*
X124271Y298704D01*
X125050Y291135D01*
X125883Y285671D01*
X125886Y285622D01*
X123960Y283696D01*
G01X602314Y602641D02*
X600389Y604566D01*
X599889D01*
X598960Y603600D01*
X599040Y601300D01*
X600017Y599684D01*
X602164Y599030D01*
X602811Y599378D01*
X604248Y598939D01*
X604593Y598291D01*
X607699Y597345D01*
X608482Y596212D01*
X609038Y595410D01*
X609523Y591394D01*
X609366Y586774D01*
X610370Y583204D01*
X611119Y582315D01*
X611894Y582250D01*
X612861Y581102D01*
X612794Y580327D01*
X614041Y578847D01*
X614184Y576837D01*
X614744Y576351D01*
X614851Y574854D01*
X614363Y574296D01*
X614470Y572799D01*
X615030Y572313D01*
X615137Y570816D01*
X614649Y570258D01*
X614853Y567356D01*
X614051Y551978D01*
X611895Y548954D01*
X597384Y541471D01*
X580767Y522330D01*
X573525Y518982D01*
X573277Y518979D01*
X573276Y518978D01*
X563185Y518874D01*
X544469Y518680D01*
X526685Y516412D01*
X514532Y517420D01*
X509720Y515794D01*
X500401Y508760D01*
X497650Y503044D01*
X498926Y481675D01*
X492523Y475663D01*
X491300Y470206D01*
X491133Y467740D01*
X490731Y463546D01*
X489241Y459400D01*
X482940Y446797D01*
X475763Y434632D01*
X469561Y430725D01*
X463249Y429321D01*
X463013D01*
X453315Y428440D01*
X453244Y428443D01*
X453237D01*
X427685Y429578D01*
X397713Y429004D01*
X397381Y429045D01*
X389170Y431337D01*
X381110Y434137D01*
X374559Y433874D01*
X356120Y436561D01*
X339813Y436350D01*
X338164Y436428D01*
X338145D01*
X338125Y436410D01*
X328605Y439338D01*
X323861Y444841D01*
X310484Y451355D01*
X287208Y454898D01*
X267637Y452243D01*
X258295Y452836D01*
X244764Y448220D01*
X223616Y451473D01*
X207908Y450822D01*
X198415Y454688D01*
X190928Y461805D01*
X181120Y463049D01*
X169530Y461442D01*
X165807Y457937D01*
X159369Y449155D01*
X158507Y448393D01*
X157719Y447697D01*
X157028Y446897D01*
X153320Y442506D01*
X151605Y401850D01*
X134641Y384228D01*
X132045Y376988D01*
X125445Y339146D01*
X126019Y303852D01*
X125428Y298697D01*
X126192Y291281D01*
X127027Y285799D01*
X127040Y285616D01*
X128960Y283696D01*
G01X173263Y262589D02*
X174196Y263544D01*
X174315Y263663D01*
Y264946D01*
X175889Y266520D01*
X180218D01*
X181805Y268107D01*
X187207D01*
X188841Y269741D01*
Y272006D01*
X193742Y276907D01*
Y279300D01*
X191111Y281931D01*
X171261D01*
X168000Y285192D01*
Y334614D01*
X171520Y338134D01*
Y357770D01*
X175432Y361682D01*
X200642D01*
X210231Y371271D01*
X232834D01*
X234805Y373242D01*
X244774D01*
X247043Y370973D01*
X308665D01*
X313769Y365869D01*
X340931D01*
X344450Y369388D01*
X358077D01*
X359060Y368405D01*
X384893D01*
X397911Y355387D01*
X399611D01*
X400135Y355911D01*
X401635D01*
X402159Y355387D01*
X403659D01*
X404183Y355911D01*
X405683D01*
X406207Y355387D01*
X407707D01*
X408231Y355911D01*
X409731D01*
X410255Y355387D01*
X411755D01*
X412279Y355911D01*
X413779D01*
X414303Y355387D01*
X415803D01*
X416327Y355911D01*
X417827D01*
X418351Y355387D01*
X419851D01*
X420375Y355911D01*
X421875D01*
X422399Y355387D01*
X425490D01*
X469886Y399783D01*
Y400569D01*
X470946Y401629D01*
X471732D01*
X472792Y402689D01*
Y403475D01*
X473852Y404535D01*
X474638D01*
X478060Y407957D01*
Y412484D01*
X476840Y413704D01*
Y423791D01*
X491450Y438401D01*
Y448974D01*
X498790Y456314D01*
Y467221D01*
X508330Y476761D01*
Y481756D01*
X515450Y488876D01*
Y500080D01*
X512826Y502704D01*
X510530D01*
X509305Y501479D01*
Y499749D01*
X509995Y499059D01*
X511230D01*
G01X176301Y262624D02*
X175465Y263441D01*
Y264469D01*
X176366Y265370D01*
X180695D01*
X182282Y266957D01*
X187684D01*
X189991Y269264D01*
Y271529D01*
X194892Y276430D01*
Y279777D01*
X191588Y283081D01*
X171738D01*
X169150Y285669D01*
Y334137D01*
X172670Y337657D01*
Y357293D01*
X175909Y360532D01*
X201119D01*
X210708Y370121D01*
X233311D01*
X235282Y372092D01*
X244297D01*
X246566Y369823D01*
X308188D01*
X313292Y364719D01*
X341408D01*
X344927Y368238D01*
X357600D01*
X358583Y367255D01*
X384416D01*
X397434Y354237D01*
X425967D01*
X479210Y407480D01*
Y412961D01*
X477990Y414181D01*
Y423314D01*
X492600Y437924D01*
Y448497D01*
X499940Y455837D01*
Y466744D01*
X509480Y476284D01*
Y481279D01*
X516600Y488399D01*
Y500557D01*
X513303Y503854D01*
X510053D01*
X508155Y501956D01*
Y499839D01*
X507375Y499059D01*
X506230D01*
G01X206299Y315748D02*
X205320Y316727D01*
Y318681D01*
X204355Y319646D01*
Y342908D01*
X211804Y350357D01*
Y356271D01*
X214721Y359188D01*
X246224D01*
X252933Y365897D01*
X272981D01*
X275857Y363021D01*
X305667D01*
X308513Y360175D01*
X336963D01*
X337865Y359273D01*
X358251D01*
X360900Y356624D01*
X387277D01*
X393990Y349911D01*
X426814D01*
X484375Y407472D01*
Y420225D01*
X486300Y422150D01*
G01X203058Y315593D02*
X204170Y316705D01*
Y318204D01*
X203205Y319169D01*
Y343385D01*
X210654Y350834D01*
Y356748D01*
X214244Y360338D01*
X245747D01*
X252456Y367047D01*
X273458D01*
X276334Y364171D01*
X306144D01*
X308990Y361325D01*
X337440D01*
X338342Y360423D01*
X358728D01*
X361377Y357774D01*
X387754D01*
X394467Y351061D01*
X426334D01*
X483225Y407952D01*
Y420225D01*
X481300Y422150D01*
G01X268064Y283696D02*
X280111D01*
X282319Y285904D01*
Y287707D01*
X284376Y289764D01*
Y293046D01*
X288657Y297327D01*
X300633D01*
X302483Y299177D01*
X329317D01*
X332994Y295500D01*
X336987D01*
X340100Y292387D01*
Y291016D01*
X341534Y289582D01*
X343950D01*
X345097Y288435D01*
X373228D01*
X407601Y322808D01*
X407606D01*
X408625Y323827D01*
X437084D01*
X438517Y325260D01*
Y325656D01*
X438516Y326052D01*
X439579Y327115D01*
X440372D01*
X441435Y328178D01*
Y328574D01*
X441434Y328970D01*
X442497Y330033D01*
X443290D01*
X444353Y331096D01*
Y331492D01*
X444352Y331888D01*
X445415Y332951D01*
X446208D01*
X447271Y334014D01*
Y334410D01*
X447270Y334806D01*
X448333Y335869D01*
X449126D01*
X450189Y336932D01*
Y337328D01*
X450188Y337724D01*
X451251Y338787D01*
X452044D01*
X453107Y339850D01*
Y340246D01*
X453106Y340642D01*
X454169Y341705D01*
X454962D01*
X456025Y342768D01*
Y343164D01*
X456024Y343560D01*
X457087Y344623D01*
X457880D01*
X499140Y385883D01*
Y386538D01*
X497111Y388567D01*
G01X268064Y282546D02*
X280588D01*
X283469Y285427D01*
Y287230D01*
X285526Y289287D01*
Y292569D01*
X289134Y296177D01*
X301110D01*
X302960Y298027D01*
X328840D01*
X332517Y294350D01*
X336510D01*
X338950Y291910D01*
Y290539D01*
X341057Y288432D01*
X343473D01*
X344620Y287285D01*
X373705D01*
X408078Y321658D01*
X408083D01*
X409102Y322677D01*
X437561D01*
X500290Y385406D01*
Y386746D01*
X502111Y388567D01*
G01X287567Y470649D02*
X288496Y469720D01*
X296440D01*
X305330Y460830D01*
X317888D01*
X318863Y461805D01*
X322458D01*
X341346Y442917D01*
X362967D01*
X363348Y443298D01*
X392536D01*
X397080Y438754D01*
X464902D01*
X476310Y450162D01*
Y452967D01*
X473390Y455887D01*
Y474246D01*
X476326Y477182D01*
X479590D01*
X480118Y477710D01*
Y479107D01*
G01X287567Y467649D02*
X288488Y468570D01*
X295963D01*
X304853Y459680D01*
X318365D01*
X319340Y460655D01*
X321981D01*
X340869Y441767D01*
X363444D01*
X363825Y442148D01*
X392059D01*
X396603Y437604D01*
X465379D01*
X477460Y449685D01*
Y453444D01*
X474540Y456364D01*
Y473769D01*
X476803Y476032D01*
X479540D01*
X480118Y475454D01*
Y474107D01*
G01X277470Y481197D02*
X278645Y482372D01*
Y484863D01*
X279277Y486242D01*
X279803Y486842D01*
X281849Y488066D01*
X282450Y488256D01*
X284088Y488388D01*
X284089D01*
X297432Y484721D01*
X305545Y486890D01*
X314060Y493607D01*
X332840Y519827D01*
X343800Y527967D01*
X353958Y545909D01*
X358044Y550582D01*
X360972Y555898D01*
X360974Y555901D01*
X361106Y556089D01*
X363921Y559409D01*
X373584Y562465D01*
X391849Y563293D01*
X392965Y563345D01*
X397216Y563783D01*
X404025Y570093D01*
X433056Y574155D01*
X449630Y572529D01*
X462415Y564670D01*
X467927Y559160D01*
X469879D01*
X471804Y561085D01*
G01X280970Y481197D02*
X279795Y482372D01*
Y484611D01*
X280253Y485610D01*
X280549Y485948D01*
X282324Y487010D01*
X282672Y487120D01*
X283979Y487225D01*
X297428Y483529D01*
X305842Y485778D01*
X306258Y485987D01*
X314901Y492804D01*
X333671Y519010D01*
X344682Y527188D01*
X354901Y545240D01*
X358992Y549918D01*
X361951Y555291D01*
X362017Y555385D01*
X364584Y558412D01*
X373787Y561323D01*
X391902Y562144D01*
X393051Y562197D01*
X397716Y562678D01*
X404542Y569004D01*
X433080Y572997D01*
X434768Y572830D01*
X435304Y572176D01*
X436798Y572029D01*
X437450Y572567D01*
X438944Y572420D01*
X439480Y571766D01*
X440974Y571619D01*
X441626Y572157D01*
X443120Y572010D01*
X443656Y571356D01*
X445150Y571209D01*
X445802Y571747D01*
X449254Y571410D01*
X461697Y563760D01*
X467450Y558010D01*
X469879D01*
X471804Y556085D01*
G01X483209Y545250D02*
X481284Y547175D01*
X472992D01*
X451282Y564433D01*
X449104Y565941D01*
X445371Y566314D01*
X444794Y565840D01*
X443300Y565992D01*
X442828Y566570D01*
X441334Y566722D01*
X440758Y566248D01*
X439264Y566400D01*
X438792Y566978D01*
X437298Y567130D01*
X436722Y566656D01*
X435228Y566808D01*
X434756Y567386D01*
X432263Y567638D01*
X431409D01*
X429828Y567499D01*
X429324Y566899D01*
X427827Y566768D01*
X427230Y567272D01*
X425734Y567141D01*
X425230Y566541D01*
X423733Y566410D01*
X423136Y566914D01*
X421640Y566783D01*
X421136Y566183D01*
X419639Y566052D01*
X419042Y566556D01*
X417546Y566425D01*
X417042Y565825D01*
X415545Y565694D01*
X414948Y566198D01*
X413452Y566067D01*
X412948Y565467D01*
X411451Y565336D01*
X410854Y565841D01*
X406378Y565451D01*
X400940Y559174D01*
X393250Y557736D01*
X378585Y557293D01*
X367187Y554254D01*
X364180Y550713D01*
X362914Y547683D01*
X356772Y539619D01*
X355228Y534565D01*
X354989Y531267D01*
X353375Y528402D01*
X346897Y521922D01*
X335254Y509525D01*
X329355Y506095D01*
X325760Y500574D01*
X312617Y483408D01*
X304686Y479635D01*
X304278Y479527D01*
X302598Y479400D01*
X299824Y477714D01*
X299261Y476302D01*
X299408Y475259D01*
X299992Y474682D01*
X302706D01*
X303631Y475607D01*
G01X483209Y550250D02*
X481284Y548325D01*
X473394D01*
X451968Y565357D01*
X449515Y567056D01*
X432321Y568788D01*
X431358D01*
X405813Y566557D01*
X400334Y560231D01*
X393126Y558883D01*
X378551Y558443D01*
X378288Y558404D01*
X366543Y555273D01*
X363187Y551322D01*
X361909Y548263D01*
X355732Y540152D01*
X354090Y534777D01*
X353860Y531607D01*
X352450Y529104D01*
X346070Y522723D01*
X334530Y510435D01*
X328540Y506952D01*
X324820Y501238D01*
X311872Y484328D01*
X304192Y480674D01*
X302236Y480526D01*
X298898Y478497D01*
X298079Y476444D01*
X298323Y474714D01*
X299519Y473532D01*
X302706D01*
X303631Y472607D01*
G54D14*
X556181Y81889D03*
G54D24*
G01X163450Y239152D02*
X162560D01*
X157419Y234011D01*
X144011D01*
X124320Y214320D01*
Y125721D01*
X131809Y118232D01*
X134456D01*
X135305Y117383D01*
Y116123D01*
X136154Y115274D01*
X137356D01*
X138205Y116123D01*
Y117383D01*
X139054Y118232D01*
X140256D01*
X141105Y117383D01*
Y116123D01*
X141954Y115274D01*
X143156D01*
X144005Y116123D01*
Y117383D01*
X144854Y118232D01*
X146056D01*
X146905Y117383D01*
Y116123D01*
X147754Y115274D01*
X148956D01*
X149805Y116123D01*
Y117383D01*
X150654Y118232D01*
X151856D01*
X152705Y117383D01*
Y116123D01*
X153554Y115274D01*
X154756D01*
X155605Y116123D01*
Y117383D01*
X156454Y118232D01*
X158704D01*
X165730Y111206D01*
Y104896D01*
X167310Y103316D01*
Y100791D01*
X168850Y99251D01*
G01X169510Y106579D02*
Y104855D01*
X171130Y103235D01*
Y98132D01*
X169570Y96572D01*
X161893D01*
X161090Y97375D01*
Y100628D01*
X159420Y102298D01*
Y103908D01*
X156107Y107221D01*
X135733D01*
X119320Y123634D01*
Y217769D01*
X140572Y239021D01*
X149150D01*
X154969Y244840D01*
X159191D01*
X161050Y246699D01*
X165331D01*
X172987Y254355D01*
G01X164280Y101810D02*
X162720Y103370D01*
Y110066D01*
X160278Y112508D01*
X158725D01*
X157876Y111659D01*
Y110673D01*
X157027Y109824D01*
X155825D01*
X154976Y110673D01*
Y111659D01*
X154127Y112508D01*
X152925D01*
X152076Y111659D01*
Y110673D01*
X151227Y109824D01*
X150025D01*
X149176Y110673D01*
Y111659D01*
X148327Y112508D01*
X147125D01*
X146276Y111659D01*
Y110673D01*
X145427Y109824D01*
X144225D01*
X143376Y110673D01*
Y111659D01*
X142527Y112508D01*
X141325D01*
X140476Y111659D01*
Y110673D01*
X139627Y109824D01*
X138425D01*
X137576Y110673D01*
Y111659D01*
X136727Y112508D01*
X133983D01*
X121820Y124671D01*
Y215881D01*
X142451Y236512D01*
X155758D01*
X156580Y237334D01*
Y238534D01*
X155420Y239694D01*
Y240894D01*
X156271Y241745D01*
X157471D01*
X158631Y240585D01*
X159831D01*
X161010Y241764D01*
X163604D01*
G01X174710Y105699D02*
Y109253D01*
X173861Y110102D01*
X169459D01*
X168610Y110951D01*
Y112153D01*
X169459Y113002D01*
X173861D01*
X174710Y113851D01*
Y115898D01*
X173747Y116861D01*
X164463D01*
X160193Y121131D01*
X132657D01*
X131598Y122190D01*
Y123390D01*
X134101Y125893D01*
Y127093D01*
X133250Y127944D01*
X132050D01*
X129547Y125441D01*
X128347D01*
X126820Y126968D01*
Y212304D01*
X146018Y231502D01*
X159832D01*
X165496Y237166D01*
X168414D01*
X172754Y241506D01*
X174971D01*
X176198Y242733D01*
Y245481D01*
X178178Y247461D01*
G01X181724Y247281D02*
Y246714D01*
X179300Y244290D01*
Y242911D01*
X175152Y238763D01*
X172923D01*
X168896Y234736D01*
X166609D01*
X160875Y229002D01*
X147222D01*
X129320Y211100D01*
Y144323D01*
X131300Y142343D01*
Y141143D01*
X129731Y139574D01*
Y138374D01*
X130582Y137523D01*
X131782D01*
X133351Y139092D01*
X134551D01*
X139570Y134073D01*
Y125145D01*
X140370Y124345D01*
X142673D01*
X143473Y125145D01*
Y129255D01*
X144322Y130104D01*
X152471D01*
X153320Y129255D01*
Y128053D01*
X152471Y127204D01*
X147222D01*
X146373Y126355D01*
Y125153D01*
X147222Y124304D01*
X161684D01*
X164490Y127110D01*
G01X184485Y245200D02*
X184480D01*
X175304Y236024D01*
X173315D01*
X169149Y231858D01*
X167273D01*
X161914Y226499D01*
X148546D01*
X131820Y209773D01*
Y161154D01*
X132669Y160305D01*
X136771D01*
X137620Y159456D01*
Y148866D01*
X136771Y148017D01*
X135569D01*
X134720Y148866D01*
Y156556D01*
X133871Y157405D01*
X132669D01*
X131820Y156556D01*
Y146433D01*
X145242Y133011D01*
X146374D01*
X147293Y133930D01*
Y135062D01*
X138581Y143774D01*
Y144974D01*
X139432Y145825D01*
X140632D01*
X158676Y127781D01*
X159190D01*
G01X168170Y123367D02*
X170020Y125217D01*
Y126877D01*
X172560Y129417D01*
Y132108D01*
X152493Y152175D01*
X151293D01*
X150442Y151324D01*
Y150124D01*
X164265Y136301D01*
Y134025D01*
X162649Y132409D01*
X160373D01*
X143196Y149586D01*
Y151862D01*
X147401Y156067D01*
Y157267D01*
X145180Y159488D01*
X143477D01*
X136380Y166585D01*
Y182235D01*
X135950Y182665D01*
Y185065D01*
X136380Y185495D01*
Y189275D01*
X135950Y189705D01*
Y192105D01*
X136380Y192535D01*
Y196315D01*
X135950Y196745D01*
Y199145D01*
X136380Y199575D01*
Y207908D01*
X140782Y212310D01*
X143018D01*
X144425Y210903D01*
X145585D01*
X146405Y211723D01*
Y212883D01*
X144998Y214290D01*
Y216526D01*
X150867Y222395D01*
X156492D01*
X158073Y220814D01*
Y218880D01*
X158673Y218280D01*
X160273D01*
X160873Y218880D01*
Y220814D01*
X162454Y222395D01*
X166450D01*
X172910Y228855D01*
Y230770D01*
X174151Y232011D01*
G01X173170Y123367D02*
X171320Y125217D01*
Y126338D01*
X173860Y128878D01*
Y132647D01*
X153032Y153475D01*
X150754D01*
X149142Y151863D01*
Y149585D01*
X162965Y135762D01*
Y134564D01*
X162110Y133709D01*
X160912D01*
X144496Y150125D01*
Y151323D01*
X148701Y155528D01*
Y157806D01*
X145719Y160788D01*
X144017D01*
X137680Y167125D01*
Y207369D01*
X141321Y211010D01*
X142479D01*
X143886Y209603D01*
X146124D01*
X147705Y211184D01*
Y213422D01*
X146298Y214829D01*
Y215987D01*
X151406Y221095D01*
X155953D01*
X156773Y220275D01*
Y218341D01*
X158134Y216980D01*
X160812D01*
X162173Y218341D01*
Y220275D01*
X162993Y221095D01*
X166989D01*
X174210Y228316D01*
Y230230D01*
X175071Y231091D01*
G01X173900Y97662D02*
X174150Y97912D01*
Y101858D01*
X177581Y105289D01*
Y110606D01*
X181370Y114395D01*
Y124353D01*
X179635Y126088D01*
Y132686D01*
X147057Y165264D01*
X145415D01*
X141680Y168999D01*
Y204782D01*
X142500Y205602D01*
X143660D01*
X144480Y204782D01*
Y188171D01*
X145300Y187351D01*
X146460D01*
X147330Y188221D01*
Y205140D01*
X155023Y212833D01*
X166299D01*
X181300Y227834D01*
Y231241D01*
X182513Y232454D01*
X184909D01*
X187209Y234754D01*
X189110D01*
G01X167383Y93147D02*
X170190D01*
Y93151D01*
X171398Y94359D01*
X177524D01*
X180290Y97125D01*
Y100378D01*
X184120Y104208D01*
Y132452D01*
X149830Y166742D01*
Y180828D01*
X149010Y181648D01*
X147850D01*
X147030Y180828D01*
Y172456D01*
X146230Y171656D01*
X145030D01*
X144230Y172456D01*
Y183628D01*
X145050Y184448D01*
X149010D01*
X149830Y185268D01*
Y204093D01*
X156068Y210331D01*
X167552D01*
X185321Y228100D01*
X187110D01*
X191500Y232490D01*
Y234862D01*
X193550Y236912D01*
Y240474D01*
X194481Y241405D01*
G01X206021Y249092D02*
X203020Y246091D01*
Y236423D01*
X201877Y235280D01*
Y231671D01*
X164430Y194224D01*
Y182619D01*
X163630Y181819D01*
X162430D01*
X161630Y182619D01*
Y185143D01*
X160830Y185943D01*
X159630D01*
X158830Y185143D01*
Y171417D01*
X198230Y132017D01*
Y123440D01*
X198233Y123437D01*
Y119781D01*
X197413Y118961D01*
X193310D01*
X192490Y118141D01*
Y116981D01*
X193310Y116161D01*
X197413D01*
X198233Y115341D01*
Y113467D01*
X197563Y112797D01*
X194203D01*
X192983Y111577D01*
Y107787D01*
X192980D01*
Y105966D01*
X200480Y98466D01*
Y97687D01*
G01X194463Y122631D02*
X193596D01*
X192560Y123667D01*
Y126275D01*
X193380Y127095D01*
X194730D01*
X195550Y127915D01*
Y129075D01*
X194730Y129895D01*
X193380D01*
X192560Y130715D01*
Y133471D01*
X156330Y169701D01*
Y187792D01*
X157150Y188612D01*
X160710D01*
X161530Y189432D01*
Y190592D01*
X160710Y191412D01*
X157150D01*
X156330Y192232D01*
Y193392D01*
X157150Y194212D01*
X160710D01*
X161530Y195032D01*
Y196192D01*
X160710Y197012D01*
X157150D01*
X156330Y197832D01*
Y200232D01*
X159472Y203374D01*
X161862D01*
X162682Y202554D01*
Y199849D01*
X163502Y199029D01*
X164662D01*
X165482Y199849D01*
Y202554D01*
X166302Y203374D01*
X170032D01*
X195880Y229222D01*
Y233041D01*
X197789Y234950D01*
X199144D01*
X201030Y236836D01*
Y244202D01*
X201032D01*
G01X203780Y233803D02*
Y229695D01*
X167410Y193325D01*
Y180101D01*
X166590Y179281D01*
X162260D01*
X161440Y178461D01*
Y177301D01*
X162260Y176481D01*
X166590D01*
X167410Y175661D01*
Y174501D01*
X166590Y173681D01*
X163020D01*
X162200Y172861D01*
Y171701D01*
X163020Y170881D01*
X166590D01*
X167410Y170061D01*
Y167287D01*
X200930Y133767D01*
Y128230D01*
X200933Y128227D01*
Y111277D01*
X199923Y110267D01*
Y107047D01*
X202433Y104537D01*
Y100567D01*
X203113Y99887D01*
Y95894D01*
X208480Y90527D01*
X215393D01*
X215773Y90147D01*
G01X204003Y91247D02*
X200764Y94486D01*
X200477D01*
X190350Y104613D01*
Y109909D01*
X189490Y110769D01*
Y123818D01*
X188390Y124918D01*
Y134087D01*
X153830Y168647D01*
Y201471D01*
X158595Y206236D01*
X169354D01*
X193380Y230262D01*
Y233853D01*
X196320Y236793D01*
Y240016D01*
X196730Y240426D01*
Y242692D01*
G01X213790Y229860D02*
X211630Y227700D01*
Y224206D01*
X195318Y207894D01*
Y206694D01*
X196541Y205471D01*
Y204271D01*
X195690Y203420D01*
X194490D01*
X193267Y204643D01*
X192067D01*
X190750Y203326D01*
Y190061D01*
X189930Y189241D01*
X188770D01*
X187950Y190061D01*
Y197340D01*
X187150Y198140D01*
X185950D01*
X185150Y197340D01*
Y179243D01*
X184330Y178423D01*
X183810D01*
X182990Y177603D01*
Y176443D01*
X183810Y175623D01*
X184330D01*
X185150Y174803D01*
Y173643D01*
X184330Y172823D01*
X178530D01*
X177710Y172003D01*
Y170843D01*
X178530Y170023D01*
X184330D01*
X185150Y169203D01*
Y162881D01*
X210570Y137461D01*
Y126854D01*
X214740Y122684D01*
Y118322D01*
X213690Y117272D01*
X211370D01*
X210570Y116472D01*
Y115272D01*
X211370Y114472D01*
X213690D01*
X214530Y113632D01*
Y112228D01*
X213203Y110901D01*
Y105737D01*
X212423Y104957D01*
G01X208908Y96975D02*
X210493Y98560D01*
Y100317D01*
X205270Y105540D01*
Y135259D01*
X171650Y168879D01*
Y191462D01*
X173232Y193044D01*
X175468D01*
X177050Y191462D01*
Y182111D01*
X177871Y181290D01*
X179029D01*
X179850Y182111D01*
Y199930D01*
X205880Y225960D01*
X205883D01*
G01X213908Y96975D02*
X211793Y99090D01*
Y100856D01*
X206570Y106079D01*
Y135798D01*
X178020Y164348D01*
Y164969D01*
X177940Y165049D01*
X177931D01*
X176234Y166746D01*
X175622D01*
X172950Y169418D01*
Y190923D01*
X173771Y191744D01*
X174929D01*
X175750Y190923D01*
Y181572D01*
X177332Y179990D01*
X179568D01*
X181150Y181572D01*
Y199391D01*
X184333Y202574D01*
X184334D01*
X206800Y225040D01*
X206803D01*
G01X219510Y101338D02*
Y103560D01*
X216520Y106550D01*
Y109980D01*
X217490Y110950D01*
Y123910D01*
X213120Y128280D01*
Y139109D01*
X193540Y158689D01*
Y182371D01*
X192720Y183191D01*
X191560D01*
X190740Y182371D01*
Y163929D01*
X189940Y163129D01*
X188740D01*
X187940Y163929D01*
Y185171D01*
X188760Y185991D01*
X192720D01*
X193540Y186811D01*
Y197455D01*
X199422Y203337D01*
Y208176D01*
X215170Y223924D01*
Y229721D01*
G01X214320Y101978D02*
X218280Y98018D01*
X220459D01*
X223430Y100989D01*
Y115621D01*
X220060Y118991D01*
Y125997D01*
X215970Y130087D01*
Y139796D01*
X196040Y159726D01*
Y164054D01*
X196860Y164874D01*
X198180D01*
X199000Y165694D01*
Y166854D01*
X198180Y167674D01*
X196860D01*
X196040Y168494D01*
Y195699D01*
X204441Y204100D01*
Y205260D01*
X202893Y206808D01*
Y207968D01*
X203713Y208788D01*
X204873D01*
X206421Y207240D01*
X207581D01*
X208401Y208060D01*
Y209220D01*
X206853Y210768D01*
Y211928D01*
X207673Y212748D01*
X208833D01*
X210381Y211200D01*
X211541D01*
X212361Y212020D01*
Y213180D01*
X210813Y214728D01*
Y215888D01*
X211633Y216708D01*
X212793D01*
X214341Y215160D01*
X215501D01*
X216321Y215980D01*
Y217140D01*
X214773Y218688D01*
Y219848D01*
X217700Y222775D01*
Y228061D01*
X218940Y229301D01*
Y243111D01*
X223416Y247587D01*
Y252487D01*
G01X243373Y88767D02*
X242933Y89207D01*
Y94317D01*
X244873Y96257D01*
Y97529D01*
X243975Y98427D01*
X242703D01*
X240066Y95790D01*
X238599D01*
X237480Y96909D01*
Y100254D01*
X234510Y103224D01*
Y111245D01*
X235323Y112058D01*
Y120203D01*
X237873Y122753D01*
Y127917D01*
X235043Y130747D01*
X228289D01*
X222980Y136056D01*
Y143213D01*
X209370Y156823D01*
Y195298D01*
X225440Y211368D01*
Y229746D01*
X227971Y232277D01*
Y235140D01*
X231245Y238414D01*
X234341D01*
X235216Y239289D01*
Y239292D01*
G01X224885Y254256D02*
X225916Y253225D01*
Y246487D01*
X221440Y242011D01*
Y217454D01*
X198540Y194554D01*
Y189844D01*
X199389Y188995D01*
X201711D01*
X202560Y188146D01*
Y186944D01*
X201711Y186095D01*
X199389D01*
X198540Y185246D01*
Y184044D01*
X199389Y183195D01*
X201711D01*
X202560Y182346D01*
Y181144D01*
X201711Y180295D01*
X199389D01*
X198540Y179446D01*
Y178244D01*
X199389Y177395D01*
X201711D01*
X202560Y176546D01*
Y175344D01*
X201711Y174495D01*
X199389D01*
X198540Y173646D01*
Y172444D01*
X199389Y171595D01*
X201711D01*
X202560Y170746D01*
Y163869D01*
X201740Y163049D01*
X199940D01*
X199120Y162229D01*
Y161069D01*
X199940Y160249D01*
X201740D01*
X202560Y159429D01*
Y157519D01*
X218470Y141609D01*
Y134517D01*
X222560Y130427D01*
Y120123D01*
X226710Y115973D01*
Y105920D01*
X226713Y105917D01*
Y100359D01*
X220711Y94357D01*
X220710D01*
X220200Y93847D01*
Y93561D01*
G01X242913Y106157D02*
X243693Y106937D01*
Y111917D01*
X243133Y112477D01*
Y114650D01*
X242313Y115470D01*
X238750D01*
X237930Y116290D01*
Y117450D01*
X238750Y118270D01*
X242313D01*
X243133Y119090D01*
Y120250D01*
X242313Y121070D01*
X241333D01*
X240513Y121890D01*
Y123050D01*
X241333Y123870D01*
X242313D01*
X243133Y124690D01*
Y126210D01*
X236092Y133251D01*
X229323D01*
X225480Y137094D01*
Y144254D01*
X211872Y157862D01*
Y159022D01*
X212692Y159842D01*
X213852D01*
X219072Y154622D01*
X220232D01*
X221052Y155442D01*
Y156602D01*
X211870Y165784D01*
Y194245D01*
X227940Y210315D01*
Y228697D01*
X230400Y231157D01*
Y234708D01*
X232283Y236591D01*
X235726D01*
X236516Y237381D01*
G01X252683Y105867D02*
X252483Y106067D01*
Y116127D01*
X248133Y120477D01*
Y136715D01*
X242513Y142335D01*
X234496D01*
X226060Y150771D01*
Y158673D01*
X219920Y164813D01*
Y186980D01*
X220740Y187800D01*
X221900D01*
X222720Y186980D01*
Y172142D01*
X223520Y171342D01*
X224720D01*
X225520Y172142D01*
Y189780D01*
X224700Y190600D01*
X220740D01*
X219920Y191420D01*
Y195204D01*
X232940Y208224D01*
Y226412D01*
X240650Y234122D01*
G01X249453Y114307D02*
Y109166D01*
X248560Y108273D01*
X247043D01*
Y108270D01*
X246243Y109070D01*
Y112917D01*
X245633Y113527D01*
Y127649D01*
X243177Y130105D01*
Y131265D01*
X245363Y133451D01*
Y134611D01*
X244543Y135431D01*
X243383D01*
X241197Y133245D01*
X240037D01*
X239217Y134065D01*
Y135225D01*
X241403Y137411D01*
Y138571D01*
X240583Y139391D01*
X239423D01*
X237237Y137205D01*
X236077D01*
X233003Y140279D01*
X231843D01*
X230711Y139147D01*
X229551D01*
X228731Y139967D01*
Y141127D01*
X229863Y142259D01*
Y143419D01*
X223560Y149722D01*
Y157630D01*
X214370Y166820D01*
Y173559D01*
X215190Y174379D01*
X216380D01*
X217200Y175199D01*
Y176359D01*
X216380Y177179D01*
X215190D01*
X214370Y177999D01*
Y179159D01*
X215190Y179979D01*
X216380D01*
X217200Y180799D01*
Y181959D01*
X216380Y182779D01*
X215190D01*
X214370Y183599D01*
Y184759D01*
X215190Y185579D01*
X216380D01*
X217200Y186399D01*
Y187559D01*
X216380Y188379D01*
X215190D01*
X214370Y189199D01*
Y193195D01*
X230440Y209265D01*
Y227457D01*
X238780Y235797D01*
Y238483D01*
G01X239563Y92077D02*
X240233Y91407D01*
Y87367D01*
X243253Y84347D01*
X262123D01*
X264823Y87047D01*
Y90717D01*
X267878Y93772D01*
Y97582D01*
X275310Y105014D01*
Y109526D01*
X282320Y116536D01*
Y129177D01*
X281500Y129997D01*
X278800D01*
X277980Y130817D01*
Y131977D01*
X278800Y132797D01*
X281500D01*
X282320Y133617D01*
Y135611D01*
X261390Y156541D01*
Y235626D01*
X262300Y236536D01*
Y237076D01*
X262305D01*
Y249320D01*
G01X253558Y95038D02*
X251708Y96888D01*
Y98903D01*
X257903Y105098D01*
Y118497D01*
X253573Y122827D01*
Y142115D01*
X248065Y147623D01*
X246734D01*
X239720Y154637D01*
Y171113D01*
X240540Y171933D01*
X241700D01*
X242520Y171113D01*
Y160539D01*
X244102Y158957D01*
X246338D01*
X247920Y160539D01*
Y175752D01*
X246339Y177333D01*
X240540D01*
X239720Y178153D01*
Y224883D01*
X243930Y229093D01*
Y230680D01*
G01X242630D02*
Y229632D01*
X238420Y225422D01*
Y206447D01*
X237940Y205967D01*
Y203567D01*
X238420Y203087D01*
Y199687D01*
X237940Y199207D01*
Y196807D01*
X238420Y196327D01*
Y192927D01*
X237940Y192447D01*
Y190047D01*
X238420Y189567D01*
Y186167D01*
X237940Y185687D01*
Y183287D01*
X238420Y182807D01*
Y177614D01*
X240001Y176033D01*
X245800D01*
X246620Y175213D01*
Y161078D01*
X245799Y160257D01*
X244641D01*
X243820Y161078D01*
Y171652D01*
X242239Y173233D01*
X240001D01*
X238420Y171652D01*
Y154098D01*
X246195Y146323D01*
X247526D01*
X252273Y141576D01*
Y122288D01*
X256603Y117958D01*
Y105637D01*
X250408Y99442D01*
Y96888D01*
X248558Y95038D01*
G01X255798Y249254D02*
Y247963D01*
X249160Y241325D01*
Y233458D01*
X247930Y232228D01*
Y227434D01*
X243720Y223224D01*
Y217152D01*
X244540Y216332D01*
X245910D01*
X246710Y215532D01*
Y214332D01*
X245910Y213532D01*
X244540D01*
X243720Y212712D01*
Y211552D01*
X244540Y210732D01*
X245490D01*
X246310Y209912D01*
Y208752D01*
X245490Y207932D01*
X244540D01*
X243720Y207112D01*
Y205952D01*
X244540Y205132D01*
X245490D01*
X246310Y204312D01*
Y203152D01*
X245490Y202332D01*
X244540D01*
X243720Y201512D01*
Y200352D01*
X244540Y199532D01*
X245490D01*
X246310Y198712D01*
Y197552D01*
X245490Y196732D01*
X244540D01*
X243720Y195912D01*
Y194752D01*
X244540Y193932D01*
X245490D01*
X246310Y193112D01*
Y191952D01*
X245490Y191132D01*
X244540D01*
X243720Y190312D01*
Y185610D01*
X244350Y184980D01*
X244352D01*
X251920Y177412D01*
Y149426D01*
X260681Y140665D01*
X266013D01*
X266833Y139845D01*
Y138685D01*
X266013Y137865D01*
X259740D01*
X258940Y137065D01*
Y135865D01*
X259740Y135065D01*
X266013D01*
X266833Y134245D01*
Y133085D01*
X266013Y132265D01*
X259920D01*
X259120Y131465D01*
Y129982D01*
X259920Y129182D01*
X267766D01*
X272860Y124088D01*
Y120106D01*
X262473Y109719D01*
Y106937D01*
G01X263683Y99902D02*
X266488D01*
X272060Y105474D01*
Y110561D01*
X279380Y117881D01*
Y124948D01*
X272463Y131865D01*
Y134708D01*
X274490Y136735D01*
Y139893D01*
X263395Y150988D01*
X262235D01*
X260477Y149229D01*
X259319D01*
X258497Y150051D01*
Y151210D01*
X260255Y152968D01*
Y154128D01*
X258890Y155493D01*
Y196533D01*
X258090Y197333D01*
X256890D01*
X256090Y196533D01*
Y184075D01*
X255270Y183255D01*
X254110D01*
X253290Y184075D01*
Y200234D01*
X254110Y201054D01*
X258070D01*
X258890Y201874D01*
Y232606D01*
X256000Y235496D01*
Y238553D01*
X257950Y240503D01*
Y242896D01*
X260051Y244997D01*
Y248883D01*
G01X257780Y248378D02*
Y246792D01*
X251560Y240572D01*
Y225232D01*
X249290Y222962D01*
Y218498D01*
X250020Y217768D01*
X253980D01*
X254890Y216858D01*
Y204487D01*
X254070Y203667D01*
X252910D01*
X252090Y204487D01*
Y211639D01*
X251290Y212439D01*
X250090D01*
X249290Y211639D01*
Y183597D01*
X254420Y178467D01*
Y150465D01*
X259806Y145079D01*
X265139D01*
X269340Y140878D01*
Y131155D01*
X275870Y124625D01*
Y118922D01*
X266083Y109135D01*
Y106307D01*
X260113Y100337D01*
Y96447D01*
X262713Y93847D01*
X263703D01*
G01X325360Y92517D02*
X325540Y92697D01*
Y95831D01*
X323033Y98338D01*
Y100403D01*
X314310Y109126D01*
X310770D01*
X308160Y111736D01*
Y123323D01*
X312506Y127669D01*
Y130590D01*
X311686Y131410D01*
X308721D01*
X307901Y132230D01*
Y133390D01*
X308721Y134210D01*
X311686D01*
X312506Y135030D01*
Y139174D01*
X311686Y139994D01*
X298736D01*
X283956Y154774D01*
X282796D01*
X281976Y153954D01*
Y152794D01*
X284743Y150027D01*
Y148867D01*
X283923Y148047D01*
X282763D01*
X278016Y152794D01*
Y153954D01*
X280816Y156754D01*
Y157914D01*
X267890Y170840D01*
Y229536D01*
X271990Y233636D01*
Y235520D01*
X272620Y236150D01*
Y238653D01*
G01X271458Y241347D02*
X271680Y241125D01*
X272979D01*
X274540Y239564D01*
Y235360D01*
X273890Y234710D01*
Y231987D01*
X270390Y228487D01*
Y179202D01*
X272928Y176664D01*
Y175504D01*
X270947Y173523D01*
Y172363D01*
X271767Y171543D01*
X272927D01*
X274908Y173524D01*
X276068D01*
X276888Y172704D01*
Y171544D01*
X274907Y169563D01*
Y168403D01*
X275727Y167583D01*
X276887D01*
X278868Y169564D01*
X280028D01*
X280848Y168744D01*
Y167584D01*
X278867Y165603D01*
Y164443D01*
X279687Y163623D01*
X280847D01*
X282828Y165604D01*
X283988D01*
X284808Y164784D01*
Y163624D01*
X282827Y161643D01*
Y160483D01*
X283647Y159663D01*
X284807D01*
X286788Y161644D01*
X287948D01*
X288768Y160824D01*
Y159664D01*
X286787Y157683D01*
Y156523D01*
X287607Y155703D01*
X288767D01*
X290748Y157684D01*
X291908D01*
X292728Y156864D01*
Y155704D01*
X290747Y153723D01*
Y152563D01*
X300468Y142842D01*
X314286D01*
X315145Y141983D01*
Y124515D01*
X316420Y123240D01*
Y112478D01*
X325080Y103818D01*
X327190D01*
G01X324070Y88861D02*
X321974Y90957D01*
X319233D01*
X318253Y89977D01*
Y88017D01*
X316133Y85897D01*
X311243D01*
X306563Y90577D01*
Y107516D01*
X304040Y110039D01*
Y117946D01*
X304041D01*
Y125124D01*
X304040Y125125D01*
Y126034D01*
X301470Y128604D01*
Y128608D01*
X300557D01*
X298290Y130875D01*
Y134600D01*
X288952Y143938D01*
X287820D01*
X286972Y143090D01*
Y141958D01*
X292523Y136407D01*
Y135247D01*
X291703Y134427D01*
X290543D01*
X275450Y149520D01*
Y159009D01*
X265390Y169069D01*
Y231233D01*
X270260Y236103D01*
Y237037D01*
G01X327430Y108208D02*
X325079D01*
X319653Y113634D01*
Y123907D01*
X318153Y125407D01*
Y143676D01*
X314528Y147301D01*
X301449D01*
X296790Y151960D01*
Y157669D01*
X292590Y161869D01*
X291270D01*
X277968Y175171D01*
Y176331D01*
X278788Y177151D01*
X279948D01*
X290375Y166724D01*
X291535D01*
X292355Y167544D01*
Y168704D01*
X279948Y181111D01*
X278788D01*
X275988Y178311D01*
X274828D01*
X272890Y180249D01*
Y183237D01*
X273710Y184057D01*
X274630D01*
X275450Y184877D01*
Y186037D01*
X274630Y186857D01*
X273710D01*
X272890Y187677D01*
Y189753D01*
X273900Y190763D01*
Y192553D01*
X272890Y193563D01*
Y195353D01*
X273900Y196363D01*
Y198153D01*
X272890Y199163D01*
Y200953D01*
X273900Y201963D01*
Y203753D01*
X272890Y204763D01*
Y206553D01*
X273900Y207563D01*
Y209353D01*
X272890Y210363D01*
Y226732D01*
X275920Y229762D01*
Y234331D01*
X279161Y237572D01*
Y237817D01*
G01X279330Y230249D02*
Y190037D01*
X282212Y187155D01*
X283370D01*
X285081Y188865D01*
X287317Y188864D01*
X288898Y187283D01*
X288899Y185047D01*
X287189Y183336D01*
Y182178D01*
X288013Y181354D01*
X289171D01*
X290418Y182602D01*
X292655Y182603D01*
X294240Y181019D01*
Y178784D01*
X292990Y177535D01*
Y176377D01*
X298487Y170880D01*
Y168644D01*
X297693Y167850D01*
Y166690D01*
X298513Y165870D01*
X299673D01*
X300467Y166664D01*
X302703D01*
X304288Y165079D01*
Y162843D01*
X301951Y160506D01*
Y159346D01*
X302771Y158526D01*
X303931D01*
X306268Y160863D01*
X308504D01*
X310089Y159278D01*
Y157042D01*
X307752Y154705D01*
Y153545D01*
X308572Y152725D01*
X309732D01*
X312069Y155062D01*
X314305D01*
X323783Y145584D01*
Y126767D01*
X326803Y123747D01*
Y117047D01*
X326800D01*
Y114287D01*
X331560Y109527D01*
Y97910D01*
X333973Y95497D01*
Y93707D01*
X334858Y92822D01*
X335668D01*
G01X278030Y230249D02*
Y217482D01*
X277550Y217002D01*
Y214602D01*
X278030Y214122D01*
Y189498D01*
X281673Y185855D01*
X283909D01*
X285619Y187564D01*
X286778D01*
X287598Y186744D01*
Y185585D01*
X285889Y183875D01*
Y181639D01*
X287474Y180054D01*
X289710D01*
X290957Y181302D01*
X292117D01*
X292940Y180480D01*
Y179323D01*
X291690Y178074D01*
Y175838D01*
X297187Y170341D01*
Y169183D01*
X296393Y168389D01*
Y166151D01*
X297974Y164570D01*
X300212D01*
X301006Y165364D01*
X302164D01*
X302988Y164540D01*
Y163382D01*
X300651Y161045D01*
Y158807D01*
X302232Y157226D01*
X304470D01*
X306807Y159563D01*
X307965D01*
X308789Y158739D01*
Y157581D01*
X306452Y155244D01*
Y153006D01*
X308033Y151425D01*
X310271D01*
X312608Y153762D01*
X313766D01*
X322483Y145045D01*
Y126228D01*
X325503Y123208D01*
Y118347D01*
X325500D01*
Y113748D01*
X330260Y108988D01*
Y97371D01*
X332673Y94958D01*
Y93607D01*
X331888Y92822D01*
X330668D01*
G01X343070Y99372D02*
X342780Y99662D01*
Y116283D01*
X339920Y119143D01*
Y152554D01*
X339913D01*
Y153530D01*
X321571Y171872D01*
X321572Y172530D01*
Y173688D01*
X320500Y174760D01*
X318683D01*
X317611Y175832D01*
X317612Y176490D01*
Y177648D01*
X316540Y178720D01*
X314723D01*
X312060Y181383D01*
Y188327D01*
X290830Y209557D01*
Y233451D01*
X291816Y234437D01*
Y242984D01*
X292016Y243184D01*
X292020D01*
Y248122D01*
X286672Y253470D01*
X279398D01*
X274564Y258304D01*
X273200D01*
G01X287104Y242388D02*
Y234664D01*
X285830Y233390D01*
Y207471D01*
X294244Y199058D01*
Y197928D01*
X293394Y197078D01*
X292262D01*
X288199Y201141D01*
X287040D01*
X286218Y200319D01*
Y199161D01*
X334580Y150799D01*
Y149142D01*
X333760Y148322D01*
X331490D01*
X330670Y147502D01*
Y146342D01*
X331490Y145522D01*
X333760D01*
X334580Y144702D01*
Y143542D01*
X333760Y142722D01*
X331490D01*
X330670Y141902D01*
Y140742D01*
X331490Y139922D01*
X333760D01*
X334580Y139102D01*
Y137942D01*
X333760Y137122D01*
X331490D01*
X330670Y136302D01*
Y135142D01*
X331490Y134322D01*
X333760D01*
X334580Y133502D01*
Y116538D01*
X337630Y113488D01*
Y106304D01*
G01X334720Y102184D02*
Y112210D01*
X331273Y115657D01*
Y119677D01*
X330423Y120527D01*
Y124757D01*
X328043Y127137D01*
Y153798D01*
X324421Y157420D01*
X323261D01*
X322006Y156165D01*
X320846D01*
X320026Y156985D01*
Y158145D01*
X321281Y159400D01*
Y160560D01*
X320461Y161380D01*
X319301D01*
X318046Y160125D01*
X316886D01*
X316066Y160945D01*
Y162105D01*
X317321Y163360D01*
Y164520D01*
X316501Y165340D01*
X315341D01*
X314086Y164085D01*
X312926D01*
X312106Y164905D01*
Y166065D01*
X313361Y167320D01*
Y168480D01*
X312541Y169300D01*
X311381D01*
X309137Y167056D01*
X307977D01*
X307157Y167876D01*
Y169036D01*
X309401Y171280D01*
Y172440D01*
X308581Y173260D01*
X307421D01*
X305724Y171563D01*
X304564D01*
X303744Y172383D01*
Y173543D01*
X305441Y175240D01*
Y176400D01*
X304621Y177220D01*
X303461D01*
X302206Y175965D01*
X301046D01*
X300226Y176785D01*
Y177945D01*
X301481Y179200D01*
Y180360D01*
X283330Y198511D01*
Y233864D01*
X284578Y235112D01*
Y242191D01*
X283942Y242827D01*
G01X288915Y242244D02*
Y233210D01*
X288330Y232625D01*
Y208514D01*
X298200Y198644D01*
X298206D01*
X309552Y187298D01*
Y186138D01*
X308732Y185318D01*
X307572D01*
X299418Y193472D01*
X298258D01*
X297438Y192652D01*
Y191492D01*
X337413Y151517D01*
Y117925D01*
X340280Y115058D01*
Y104971D01*
X338240Y102931D01*
Y100276D01*
X340543Y97973D01*
Y88647D01*
G01X286132Y285953D02*
X289026Y283059D01*
Y277170D01*
X290986Y275210D01*
X290993D01*
Y274050D01*
X290994D01*
X289220Y272276D01*
Y271195D01*
X290519Y269896D01*
X291779D01*
X294073Y272190D01*
X295233D01*
X296908Y270515D01*
X301548D01*
X305130Y266933D01*
X316469D01*
X321770Y261632D01*
Y241254D01*
X323400Y239624D01*
X323406D01*
X380909Y182121D01*
Y180961D01*
X380089Y180141D01*
X378929D01*
X357748Y201322D01*
X356588D01*
X355768Y200502D01*
Y199342D01*
X381800Y173310D01*
Y138974D01*
X380643Y137817D01*
Y119847D01*
X379540Y118744D01*
Y106794D01*
X378733Y105987D01*
G01X382087Y103647D02*
Y105613D01*
X382097Y105623D01*
X382103D01*
X382233Y105753D01*
Y117897D01*
X383143Y118807D01*
Y136077D01*
X384300Y137234D01*
Y182267D01*
X357120Y209447D01*
X357123Y209450D01*
Y217366D01*
X336422Y238067D01*
X335263D01*
X334442Y237246D01*
Y236086D01*
X354094Y216434D01*
Y215274D01*
X353273Y214453D01*
X352115D01*
X325035Y241532D01*
Y254420D01*
X325855Y255240D01*
X326940D01*
X327760Y256060D01*
Y257220D01*
X326940Y258040D01*
X325855D01*
X325035Y258860D01*
Y263039D01*
X318634Y269440D01*
X305507D01*
X301495Y273452D01*
X298904D01*
X298010Y274346D01*
Y275806D01*
X296270Y277546D01*
X292900D01*
X292128Y278318D01*
Y284317D01*
X290363Y286082D01*
G01X294830Y244947D02*
Y211233D01*
X316060Y190003D01*
Y184865D01*
X326019Y174906D01*
Y173537D01*
X344600Y154956D01*
Y128750D01*
X346780Y126570D01*
Y103274D01*
X347240Y102814D01*
Y102579D01*
X348200Y101619D01*
Y90154D01*
X347173Y89127D01*
Y83957D01*
X348243Y82887D01*
X351924D01*
X352744Y83707D01*
Y87983D01*
X353564Y88803D01*
X354724D01*
X355544Y87983D01*
Y83707D01*
X356364Y82887D01*
X361183D01*
X362133Y83837D01*
Y90877D01*
G01X361470Y101757D02*
X360068Y100355D01*
Y96280D01*
X359290Y95502D01*
X358098D01*
X358097Y95495D01*
X357268Y96324D01*
Y100256D01*
X356468Y101056D01*
X355268D01*
X354468Y100256D01*
Y96732D01*
X353668Y95932D01*
X352468D01*
X351668Y96732D01*
Y101925D01*
X349283Y104310D01*
Y121727D01*
X349280Y121730D01*
Y128590D01*
X347100Y130770D01*
Y142046D01*
X347920Y142866D01*
X349313D01*
X350133Y143686D01*
Y144846D01*
X349313Y145666D01*
X347920D01*
X347100Y146486D01*
Y147646D01*
X347920Y148466D01*
X349313D01*
X350133Y149286D01*
Y150446D01*
X349313Y151266D01*
X347920D01*
X347100Y152086D01*
Y156834D01*
X346163Y157771D01*
Y159159D01*
X344877Y160445D01*
X343489D01*
X342203Y161731D01*
Y163119D01*
X340917Y164405D01*
X339529D01*
X338243Y165691D01*
Y167079D01*
X336957Y168365D01*
X335569D01*
X334283Y169651D01*
Y171039D01*
X332997Y172325D01*
X331609D01*
X329640Y174294D01*
Y176711D01*
X318970Y187381D01*
Y190629D01*
X297330Y212269D01*
Y231423D01*
G01X354943Y104191D02*
Y104974D01*
X351793Y108124D01*
Y111451D01*
X352510Y112168D01*
Y121384D01*
X353873Y122747D01*
Y133552D01*
X353870D01*
Y137370D01*
X352890Y138350D01*
Y151970D01*
X350070Y154790D01*
Y159826D01*
X345665Y164231D01*
Y165391D01*
X346144Y165870D01*
Y167030D01*
X345324Y167850D01*
X344164D01*
X343685Y167371D01*
X342525D01*
X341705Y168191D01*
Y169351D01*
X343094Y170740D01*
Y171872D01*
X342246Y172720D01*
X341114D01*
X339725Y171331D01*
X338565D01*
X337745Y172151D01*
Y173311D01*
X338974Y174540D01*
Y175672D01*
X338126Y176520D01*
X336994D01*
X335765Y175291D01*
X334605D01*
X333785Y176111D01*
Y177271D01*
X334192Y177678D01*
Y178838D01*
X333372Y179658D01*
X332212D01*
X331805Y179251D01*
X330645D01*
X329825Y180071D01*
Y181231D01*
X330232Y181638D01*
Y182798D01*
X329412Y183618D01*
X328252D01*
X327845Y183211D01*
X326685D01*
X325865Y184031D01*
Y185191D01*
X326272Y185598D01*
Y186758D01*
X325452Y187578D01*
X324292D01*
X323885Y187171D01*
X322725D01*
X321470Y188426D01*
Y191668D01*
X299830Y213308D01*
Y230482D01*
G01X301916Y248778D02*
Y232357D01*
X303830Y230443D01*
Y216694D01*
X311650Y208874D01*
Y208202D01*
X313348Y206504D01*
X314020D01*
X316540Y203984D01*
Y203304D01*
X316548D01*
X318246Y201606D01*
X318918D01*
X321440Y199084D01*
Y198406D01*
X321446D01*
X323144Y196708D01*
X323816D01*
X326340Y194184D01*
Y193508D01*
X326344D01*
X328042Y191810D01*
X328714D01*
X331240Y189284D01*
Y188610D01*
X331242D01*
X332940Y186912D01*
X333612D01*
X338175Y182349D01*
X341523D01*
X342391Y181481D01*
Y178133D01*
X343976Y176548D01*
X347256D01*
X348192Y175612D01*
Y170767D01*
X353687Y165272D01*
X360733D01*
X361553Y164452D01*
Y163292D01*
X360733Y162472D01*
X355721D01*
X354160Y160911D01*
Y156469D01*
X356082Y154547D01*
X357324D01*
X357963Y153908D01*
Y115742D01*
X357143Y114922D01*
Y107329D01*
X359931Y104541D01*
X362243D01*
X364820Y101964D01*
Y96768D01*
X366901Y94687D01*
X368824D01*
X369533Y93978D01*
Y92967D01*
X368312Y91746D01*
X367776D01*
G01X303216Y248778D02*
Y232896D01*
X305130Y230982D01*
Y217234D01*
X332940Y189424D01*
Y189423D01*
X338714Y183649D01*
X342062D01*
X343691Y182020D01*
Y178672D01*
X344515Y177848D01*
X345673D01*
X347795Y177849D01*
X349493Y176151D01*
X349492Y174029D01*
Y171306D01*
X354226Y166572D01*
X361272D01*
X362853Y164991D01*
Y162753D01*
X361272Y161172D01*
X356260D01*
X355460Y160372D01*
Y157008D01*
X356621Y155847D01*
X357863D01*
X359263Y154447D01*
Y115203D01*
X358443Y114383D01*
Y107868D01*
X360470Y105841D01*
X362783D01*
X366120Y102504D01*
Y97307D01*
X367440Y95987D01*
X369363D01*
X370833Y94517D01*
Y92567D01*
X371654Y91746D01*
X372776D01*
G01X369670Y99845D02*
Y103385D01*
X365710Y107345D01*
Y109663D01*
X364861Y110512D01*
X363719D01*
X362870Y111361D01*
Y112563D01*
X363719Y113412D01*
X364861D01*
X365710Y114261D01*
Y116526D01*
X363330Y118906D01*
Y154086D01*
X364812Y155568D01*
X366014D01*
X366900Y156454D01*
Y166610D01*
X361986Y171524D01*
X360786D01*
X359988Y170726D01*
X358788D01*
X357937Y171577D01*
Y172777D01*
X358735Y173575D01*
Y174775D01*
X357884Y175626D01*
X356684D01*
X355886Y174828D01*
X354686D01*
X353835Y175679D01*
Y176879D01*
X354633Y177677D01*
Y178877D01*
X351046Y182464D01*
X349886D01*
X349560Y182138D01*
X348400D01*
X347580Y182958D01*
Y184118D01*
X347906Y184444D01*
Y185604D01*
X345853Y187657D01*
X340376D01*
X309130Y218903D01*
Y232642D01*
X305840Y235932D01*
Y256173D01*
X301511Y260502D01*
Y262204D01*
G01X367350Y123927D02*
X367610Y124187D01*
Y150496D01*
X369600Y152486D01*
Y167451D01*
X346885Y190166D01*
X341403D01*
X336868Y194701D01*
Y195901D01*
X338474Y197507D01*
Y198707D01*
X337623Y199558D01*
X336423D01*
X334817Y197952D01*
X333617D01*
X332766Y198803D01*
Y200003D01*
X334372Y201609D01*
Y202809D01*
X333521Y203660D01*
X332321D01*
X330715Y202054D01*
X329515D01*
X328664Y202905D01*
Y204105D01*
X330270Y205711D01*
Y206911D01*
X329419Y207762D01*
X328219D01*
X326613Y206156D01*
X325413D01*
X324562Y207007D01*
Y208207D01*
X326168Y209813D01*
Y211013D01*
X325317Y211864D01*
X324117D01*
X322511Y210258D01*
X321311D01*
X320460Y211109D01*
Y212309D01*
X322066Y213915D01*
Y215115D01*
X321215Y215966D01*
X320015D01*
X318409Y214360D01*
X317209D01*
X316358Y215211D01*
Y216411D01*
X317964Y218017D01*
Y219217D01*
X317113Y220068D01*
X315913D01*
X314307Y218462D01*
X313107D01*
X311630Y219939D01*
Y226610D01*
X312450Y227430D01*
X314920D01*
X315740Y228250D01*
Y229410D01*
X314920Y230230D01*
X312450D01*
X311630Y231050D01*
Y233686D01*
X308710Y236606D01*
Y251762D01*
X309530Y252582D01*
X311010D01*
X311830Y253402D01*
Y254562D01*
X311010Y255382D01*
X309530D01*
X308710Y256202D01*
Y257486D01*
X303681Y262515D01*
G01X302620Y266660D02*
X306664Y262616D01*
X315122D01*
X317520Y260218D01*
Y239468D01*
X339811Y217177D01*
X340185D01*
X352673Y204689D01*
Y203529D01*
X351853Y202709D01*
X350693D01*
X340936Y212466D01*
X339776D01*
X338956Y211646D01*
Y210486D01*
X377750Y171692D01*
Y147976D01*
X375360Y145586D01*
Y109520D01*
X376100Y108780D01*
G01X305322Y277819D02*
X308691Y274450D01*
X321780D01*
X334800Y261430D01*
Y251657D01*
X332790Y249647D01*
Y247413D01*
X334719Y245484D01*
X337495D01*
X379818Y203161D01*
Y202001D01*
X377018Y199201D01*
Y198041D01*
X384045Y191014D01*
X385205D01*
X386025Y191834D01*
Y192994D01*
X380978Y198041D01*
Y199201D01*
X381798Y200021D01*
X382958D01*
X389300Y193679D01*
Y135151D01*
X388313Y134164D01*
Y126717D01*
X388953Y126077D01*
Y124143D01*
X389773Y123323D01*
X398510D01*
X399310Y122523D01*
X399313D01*
Y121323D01*
X399310D01*
X398510Y120523D01*
X389773D01*
X388953Y119703D01*
Y117183D01*
X389773Y116363D01*
X391750D01*
X392570Y115543D01*
Y114383D01*
X391750Y113563D01*
X389773D01*
X388953Y112743D01*
Y101927D01*
X391310Y99570D01*
G01X391233Y96093D02*
X393593Y98453D01*
Y111738D01*
X398192Y116337D01*
X399943D01*
X402690Y119084D01*
Y125605D01*
X403510Y126425D01*
X407350D01*
X408170Y127245D01*
Y128405D01*
X407350Y129225D01*
X403510D01*
X402690Y130045D01*
Y133241D01*
X404273Y134824D01*
X405431D01*
X407560Y132694D01*
X408718D01*
X409540Y133516D01*
Y134674D01*
X407411Y136804D01*
Y137962D01*
X408890Y139441D01*
Y148572D01*
X398750Y158712D01*
Y199495D01*
X375280Y222965D01*
Y247533D01*
X352421Y270392D01*
X339224D01*
X325706Y283910D01*
X310405D01*
Y283915D01*
G01X384863Y95437D02*
X383873Y94447D01*
X382252D01*
X381550Y93745D01*
X381553D01*
Y91855D01*
X381550D01*
X382388Y91017D01*
X386903D01*
X387923Y92037D01*
Y96040D01*
X386800Y97163D01*
Y99310D01*
X385563Y100547D01*
Y104617D01*
X386453Y105507D01*
Y125027D01*
X385813Y125667D01*
Y135207D01*
X386800Y136194D01*
Y183308D01*
X359623Y210485D01*
Y211645D01*
X360443Y212465D01*
X361603D01*
X372450Y201618D01*
X373610D01*
X374430Y202438D01*
Y203598D01*
X360790Y217238D01*
Y218646D01*
X337577Y241859D01*
X333543D01*
X329490Y245912D01*
Y251431D01*
X331140Y253081D01*
Y260478D01*
X319673Y271945D01*
X306660D01*
X301723Y276882D01*
Y279150D01*
G01X308280Y291424D02*
X329965D01*
X343483Y277906D01*
X355528D01*
X382780Y250654D01*
Y229857D01*
X408500Y204137D01*
Y159606D01*
X417040Y151066D01*
Y109599D01*
X411720Y104279D01*
X410560D01*
X409621Y105218D01*
X408462D01*
X407640Y104396D01*
Y103238D01*
X408581Y102298D01*
Y101140D01*
X406618Y99177D01*
X400163D01*
G01X399613Y104657D02*
Y103447D01*
X400413Y102647D01*
X402363D01*
X403163Y103447D01*
Y110707D01*
X407687Y115231D01*
X408847D01*
X411751Y112327D01*
X412883D01*
X413731Y113175D01*
Y114307D01*
X410827Y117211D01*
Y118371D01*
X414540Y122084D01*
Y150012D01*
X406000Y158552D01*
Y199331D01*
X400769Y204562D01*
Y205722D01*
X401489Y206442D01*
Y207602D01*
X400669Y208422D01*
X399509D01*
X398789Y207702D01*
X397629D01*
X396809Y208522D01*
Y209682D01*
X397529Y210402D01*
Y211562D01*
X396709Y212382D01*
X395549D01*
X394829Y211662D01*
X393669D01*
X392849Y212482D01*
Y213642D01*
X393569Y214362D01*
Y215522D01*
X392749Y216342D01*
X391589D01*
X390869Y215622D01*
X389709D01*
X388889Y216442D01*
Y217602D01*
X389609Y218322D01*
Y219482D01*
X388789Y220302D01*
X387629D01*
X386909Y219582D01*
X385749D01*
X384929Y220402D01*
Y221562D01*
X385649Y222282D01*
Y223442D01*
X384829Y224262D01*
X383669D01*
X382949Y223542D01*
X381789D01*
X380280Y225051D01*
Y249613D01*
X354493Y275400D01*
X342132D01*
X328614Y288918D01*
X310311D01*
G01X312717Y279755D02*
X324195D01*
X337561Y266389D01*
X350765D01*
X353492Y263662D01*
Y261426D01*
X351872Y259806D01*
Y258646D01*
X352692Y257826D01*
X353852D01*
X355472Y259446D01*
X357708D01*
X371280Y245874D01*
Y242278D01*
X369699Y240697D01*
X363900D01*
X363080Y239877D01*
Y227609D01*
X363900Y226789D01*
X365060D01*
X365880Y227609D01*
Y236316D01*
X367461Y237897D01*
X369699D01*
X371280Y236316D01*
Y221295D01*
X394750Y197825D01*
Y153939D01*
X395570Y153119D01*
X398669D01*
X400250Y151538D01*
Y149300D01*
X398669Y147719D01*
X395570D01*
X394750Y146899D01*
Y145739D01*
X395570Y144919D01*
X403308D01*
X404890Y143337D01*
Y141101D01*
X403308Y139519D01*
X395570D01*
X394750Y138699D01*
Y135998D01*
X396330Y134418D01*
Y130211D01*
X398086Y128455D01*
X398088D01*
G01X392493Y92647D02*
X396423Y96577D01*
Y110757D01*
X398673Y113007D01*
X400283D01*
X406857Y119581D01*
Y120741D01*
X405881Y121717D01*
Y122877D01*
X406701Y123697D01*
X407861D01*
X408837Y122721D01*
X409997D01*
X412040Y124764D01*
Y148959D01*
X401250Y159749D01*
Y160914D01*
X402070Y161734D01*
X402680D01*
X403500Y162554D01*
Y163714D01*
X402680Y164534D01*
X402070D01*
X401250Y165354D01*
Y166514D01*
X402070Y167334D01*
X402680D01*
X403500Y168154D01*
Y169314D01*
X402680Y170134D01*
X402070D01*
X401250Y170954D01*
Y172114D01*
X402070Y172934D01*
X402680D01*
X403500Y173754D01*
Y174914D01*
X402680Y175734D01*
X402070D01*
X401250Y176554D01*
Y177714D01*
X402070Y178534D01*
X402680D01*
X403500Y179354D01*
Y180514D01*
X402680Y181334D01*
X402070D01*
X401250Y182154D01*
Y183314D01*
X402070Y184134D01*
X402680D01*
X403500Y184954D01*
Y186114D01*
X402680Y186934D01*
X402070D01*
X401250Y187754D01*
Y188914D01*
X402070Y189734D01*
X402680D01*
X403500Y190554D01*
Y191714D01*
X402680Y192534D01*
X402070D01*
X401250Y193354D01*
Y194514D01*
X402070Y195334D01*
X402680D01*
X403500Y196154D01*
Y197314D01*
X402680Y198134D01*
X402070D01*
X401250Y198954D01*
Y200539D01*
X377780Y224009D01*
Y248575D01*
X353461Y272894D01*
X341097D01*
X327573Y286418D01*
X310325D01*
G01X312717Y278455D02*
X323656D01*
X337022Y265089D01*
X350226D01*
X352192Y263123D01*
Y261965D01*
X350572Y260345D01*
Y258107D01*
X352153Y256526D01*
X354391D01*
X356011Y258146D01*
X357169D01*
X369980Y245335D01*
Y242817D01*
X369160Y241997D01*
X363361D01*
X361780Y240416D01*
Y227070D01*
X363361Y225489D01*
X365599D01*
X367180Y227070D01*
Y235777D01*
X368000Y236597D01*
X369160D01*
X369980Y235777D01*
Y220756D01*
X373530Y217206D01*
Y216727D01*
X373531D01*
X375227Y215031D01*
X375705D01*
X378200Y212536D01*
Y212057D01*
X378201D01*
X379897Y210361D01*
X380375D01*
X393450Y197286D01*
Y153400D01*
X395031Y151819D01*
X398130D01*
X398950Y150999D01*
Y149839D01*
X398130Y149019D01*
X395031D01*
X393450Y147438D01*
Y145200D01*
X395031Y143619D01*
X402769D01*
X403590Y142798D01*
Y141640D01*
X402769Y140819D01*
X395031D01*
X393450Y139238D01*
Y135459D01*
X395030Y133879D01*
Y130304D01*
X393181Y128455D01*
X393088D01*
G01X380483Y99047D02*
X378978D01*
X375990Y102035D01*
Y104809D01*
X372680Y108119D01*
Y147078D01*
X375200Y149598D01*
Y170706D01*
X336190Y209716D01*
Y217259D01*
X314550Y238899D01*
Y256483D01*
X312680Y258353D01*
G01X376723Y94178D02*
X376720Y94181D01*
Y97314D01*
X372791Y101243D01*
Y104354D01*
X370170Y106975D01*
Y148111D01*
X372100Y150041D01*
Y170268D01*
X331786Y210582D01*
Y211742D01*
X333284Y213240D01*
Y214400D01*
X332464Y215220D01*
X331304D01*
X329806Y213722D01*
X328646D01*
X327408Y214960D01*
Y216160D01*
X329314Y218066D01*
Y219266D01*
X328463Y220117D01*
X327263D01*
X325357Y218211D01*
X324157D01*
X323306Y219062D01*
Y220262D01*
X325212Y222168D01*
Y223368D01*
X324361Y224219D01*
X323161D01*
X321255Y222313D01*
X320055D01*
X319204Y223164D01*
Y224364D01*
X321110Y226270D01*
Y228309D01*
X312020Y237399D01*
Y246519D01*
X311290Y247249D01*
G54D15*
X590999Y77041D03*
Y84915D03*
X615657Y77041D03*
Y84915D03*
G54D25*
G01X-39858Y731383D02*
X-36392Y727917D01*
G01X-35242Y727999D02*
X-31858Y731383D01*
G01X550604Y168072D02*
X539003Y156471D01*
X520133D01*
X503262Y139600D01*
X499158D01*
X496690Y137132D01*
X487561D01*
X476260Y125831D01*
Y121403D01*
X471070Y116213D01*
Y75663D01*
X448038Y52631D01*
X447210Y51806D01*
X346253D01*
X339183Y58880D01*
X260942D01*
X259480Y60342D01*
X255740D01*
X255667Y60269D01*
X252040D01*
X251108Y61201D01*
X170450D01*
X168763Y59514D01*
X158899D01*
X157725Y60688D01*
X155553D01*
X147300Y52435D01*
Y51170D01*
X145098Y48968D01*
X143534D01*
X139730Y45164D01*
X87774D01*
X81445Y38835D01*
X50706D01*
X36567Y52974D01*
Y73145D01*
G01X563129Y178369D02*
Y173449D01*
X539370Y149690D01*
X537940D01*
X537220Y150410D01*
X519376D01*
X501680Y132714D01*
Y132709D01*
X498902D01*
X493965Y127772D01*
X489075D01*
X474890Y113587D01*
Y73983D01*
X474830Y73923D01*
Y73914D01*
X448676Y47760D01*
X344480D01*
X337110Y55130D01*
X261987D01*
X258820Y51963D01*
X257380D01*
X256370Y52973D01*
Y54455D01*
X254306Y56519D01*
X250482D01*
X249550Y57451D01*
X172027D01*
X169257Y54681D01*
X159081D01*
X149620Y45220D01*
X146680D01*
Y45218D01*
X145387D01*
X142800Y42631D01*
Y40554D01*
X141363Y39117D01*
X87045D01*
X84480Y36552D01*
Y36548D01*
X83017Y35085D01*
X83020D01*
Y35084D01*
X81970D01*
X81969Y35085D01*
X49120D01*
X31497Y52708D01*
X31490D01*
Y52717D01*
X30535Y53672D01*
Y101956D01*
X36567Y107988D01*
G01X32260Y96899D02*
Y53745D01*
X49670Y36335D01*
X82495D01*
X86624Y40464D01*
X132717D01*
X134820Y42567D01*
X140669D01*
X144570Y46468D01*
X146160D01*
Y46470D01*
X149095D01*
X158556Y55931D01*
X168730D01*
X171500Y58701D01*
X250068D01*
X251000Y57769D01*
X256707D01*
X256780Y57842D01*
X258215D01*
X259677Y56380D01*
X337630D01*
X344704Y49306D01*
X448249D01*
X473570Y74627D01*
Y114035D01*
X488827Y129292D01*
X493468D01*
X498135Y133959D01*
X501157D01*
X521169Y153971D01*
X540711D01*
X559646Y172906D01*
Y174476D01*
G01X555510Y173872D02*
Y170538D01*
X540193Y155221D01*
X520651D01*
X503780Y138350D01*
X499676D01*
X496818Y135492D01*
X493259D01*
X472320Y114553D01*
Y75145D01*
X447731Y50556D01*
X345729D01*
X338655Y57630D01*
X260202D01*
X258740Y59092D01*
X256260D01*
X256187Y59019D01*
X251520D01*
X250588Y59951D01*
X170977D01*
X168264Y57238D01*
X154463D01*
X150750Y53525D01*
Y51005D01*
X147465Y47720D01*
X145636D01*
X145634Y47718D01*
X144052D01*
X140248Y43914D01*
X134389D01*
X132189Y41714D01*
X86101D01*
X81972Y37585D01*
X50188D01*
X34008Y53765D01*
Y91017D01*
G01X557668Y176534D02*
X550948D01*
X534527Y160113D01*
X520239D01*
X502226Y142100D01*
X498122D01*
X496114Y140092D01*
X484955D01*
X468570Y123707D01*
Y78963D01*
X457716Y68109D01*
X456860D01*
X455850Y67099D01*
Y66243D01*
X443913Y54306D01*
X347293D01*
X340226Y61380D01*
X261982D01*
X260520Y62842D01*
X258164D01*
Y62885D01*
X256080Y64969D01*
X253090D01*
X252681Y64560D01*
X151265D01*
X147220Y60515D01*
Y58273D01*
X140695Y51748D01*
Y49678D01*
X138922Y47908D01*
X86974D01*
X80401Y41335D01*
X51742D01*
X40940Y52137D01*
Y56927D01*
X43410Y59397D01*
Y80347D01*
X39126Y84631D01*
G01X41685Y73110D02*
X39690Y71115D01*
Y51619D01*
X51224Y40085D01*
X80922D01*
X87251Y46414D01*
X139208D01*
X143076Y50282D01*
X143140Y50218D01*
X144580D01*
X145590Y51228D01*
Y52658D01*
X145528Y52720D01*
X155995Y63187D01*
X251422D01*
X253090Y61519D01*
X254530D01*
X254603Y61592D01*
X260000D01*
X261462Y60130D01*
X339703D01*
X346772Y53056D01*
X446692D01*
X447520Y53881D01*
X469820Y76181D01*
Y123189D01*
X485323Y138692D01*
X496482D01*
X498640Y140850D01*
X502744D01*
X519616Y157722D01*
X534010D01*
X550460Y174172D01*
X551395D01*
G01X171616Y467804D02*
X162488D01*
X145180Y450496D01*
Y429012D01*
X141258Y425090D01*
X139395D01*
G01X150902Y379714D02*
X154010D01*
X156590Y382294D01*
Y385271D01*
X160230Y388911D01*
X166744D01*
X189051Y411218D01*
X255070D01*
X255948Y412096D01*
X282873D01*
X298906Y428129D01*
X318295D01*
X318799Y427625D01*
X331990D01*
X332961Y426654D01*
X341521D01*
X349706Y418469D01*
X394304D01*
X413947Y398826D01*
X459418D01*
X463251Y402659D01*
X465913D01*
G01X160886Y380294D02*
X162405Y378776D01*
X185882D01*
X191500Y384394D01*
Y397350D01*
X194410Y400260D01*
Y403729D01*
X195700Y405019D01*
X230583D01*
X235340Y400262D01*
X253003D01*
X258442Y405701D01*
X284983D01*
X299035Y419753D01*
X320684D01*
X323641Y416796D01*
X332321D01*
X334695Y414422D01*
X344276D01*
X345819Y412879D01*
X371260D01*
G01X162335Y543954D02*
X167790Y546339D01*
X169800D01*
X172789Y549328D01*
X175245Y550815D01*
X176162Y554312D01*
X177033Y555183D01*
X208929D01*
X214739Y551731D01*
X215474Y551183D01*
X218008Y549294D01*
Y549292D01*
X220709Y546153D01*
X229626Y537236D01*
X230476D01*
G01X159185Y537654D02*
X164771Y541985D01*
X167339Y544553D01*
X169957D01*
X174485Y549081D01*
X176183D01*
X176868Y548396D01*
X178330D01*
X186042Y551342D01*
X187486Y551594D01*
X198100Y553444D01*
X208430D01*
X215474Y548995D01*
X217354Y547808D01*
X229509Y535653D01*
X229569D01*
G01X230854D02*
X232060D01*
X233626Y534087D01*
G01X465883Y399834D02*
X463825Y397776D01*
X413512D01*
X393963Y417325D01*
X349360D01*
X344715Y421970D01*
X336155D01*
X331550Y426575D01*
X315511D01*
X312589Y423653D01*
X297200D01*
X283693Y410146D01*
X256760D01*
X255882Y409268D01*
X192186D01*
X185310Y402392D01*
Y390882D01*
X175155Y380727D01*
G01X319478Y429389D02*
X297232D01*
X281889Y414046D01*
X255138D01*
X254842Y413750D01*
X183636D01*
X173381Y424005D01*
G01X178094Y531365D02*
X180501D01*
X183216Y528650D01*
Y524507D01*
X188759Y518964D01*
Y517653D01*
X191520Y514892D01*
X199522D01*
X204209Y519579D01*
Y522053D01*
X203501Y522761D01*
Y529771D01*
X204748Y531018D01*
X220144D01*
X221730Y529432D01*
X231982D01*
X233626Y527788D01*
G01X166297Y532416D02*
X167632Y533751D01*
X179216D01*
X180659Y532308D01*
X181831D01*
X185317Y528822D01*
X186790Y524140D01*
X190967Y519963D01*
Y519095D01*
X193090Y516972D01*
X198670D01*
X201736Y520038D01*
Y530449D01*
X204060Y532773D01*
X221270D01*
X223344Y530699D01*
X233865D01*
X236776Y527788D01*
G01X174105Y542290D02*
X174835Y543020D01*
X177985D01*
X180903Y545938D01*
X185806Y547233D01*
X187641D01*
X189751Y545123D01*
X196079D01*
X197622Y546666D01*
X205573D01*
X212937Y539302D01*
X216021D01*
X217183Y538140D01*
Y537393D01*
X216519Y536729D01*
X212342D01*
G01X230476Y534087D02*
X227502D01*
X225190Y536399D01*
X222943D01*
X218390Y540952D01*
X213622D01*
X205621Y548953D01*
X186070D01*
X180639Y547268D01*
X178012Y544641D01*
X171781D01*
X169846Y542706D01*
X168243D01*
G01X229752Y538810D02*
X223559Y545003D01*
X214609Y556453D01*
X213627Y557435D01*
X192039D01*
X190248Y559226D01*
X180813D01*
X174717Y556112D01*
X171627Y553022D01*
X169157Y549066D01*
Y548676D01*
G01X164259Y557273D02*
X165301Y556748D01*
X170184D01*
X174441Y558944D01*
X180285Y560876D01*
X202727D01*
X204420Y559183D01*
X214792D01*
X215800Y558175D01*
X224458Y546502D01*
X228998Y541962D01*
G01X232052D02*
X233626Y543536D01*
G01X169444Y558757D02*
X172948Y560222D01*
X179983Y562678D01*
X203673D01*
X205518Y560833D01*
X215711D01*
X217988Y558556D01*
X221379Y553850D01*
X226709Y546453D01*
X229626Y543536D01*
X230476D01*
G01X172889Y562710D02*
X179191Y564328D01*
X216245D01*
X220683Y559890D01*
X228809Y546056D01*
X229745Y545120D01*
G01X185074Y380726D02*
X188380Y384032D01*
Y401105D01*
X194244Y406969D01*
X235046D01*
X237711Y404304D01*
X253911D01*
X257585Y407978D01*
X284284D01*
X298009Y421703D01*
X314628D01*
X316425Y423500D01*
X317855D01*
X319209Y422146D01*
X332890D01*
X335334Y419702D01*
X343130D01*
X347958Y414874D01*
X365850D01*
G01X182132Y418327D02*
X185659Y414800D01*
X254310D01*
X255285Y415775D01*
X280570D01*
X295234Y430439D01*
X306107D01*
X308220Y432552D01*
G01X184843Y533995D02*
Y531842D01*
X188639Y528046D01*
Y525260D01*
X189952Y523947D01*
X195453D01*
X196133Y523267D01*
Y522483D01*
X195147Y521497D01*
X193928D01*
X193210Y520779D01*
Y519765D01*
X193928Y519047D01*
X196968D01*
X200076Y522155D01*
Y531220D01*
X203306Y534450D01*
X223277D01*
X225361Y532366D01*
X235055D01*
X236776Y534087D01*
G01X199539Y537112D02*
X197576Y535149D01*
Y526779D01*
X197023Y526226D01*
X192375D01*
X191657Y526944D01*
Y527958D01*
X192375Y528676D01*
X194676D01*
X195126Y529126D01*
Y530676D01*
X194676Y531126D01*
X193632D01*
X193182Y531576D01*
Y533126D01*
X193632Y533576D01*
X194676D01*
X195126Y534026D01*
Y535316D01*
X194246Y536196D01*
X191889D01*
X191685Y535992D01*
X188035D01*
X187474Y536553D01*
X185909D01*
X185212Y535856D01*
X182257D01*
X181232Y536881D01*
Y537654D01*
G01X225973Y262197D02*
X227598Y263822D01*
Y271542D01*
X226329Y272811D01*
Y275124D01*
X227644Y276439D01*
X242467D01*
X243200Y275706D01*
X245505D01*
X248690Y278891D01*
X253980D01*
X259505Y284416D01*
Y289770D01*
X261245Y291510D01*
X266023D01*
X268037Y289496D01*
X273278D01*
X289863Y306081D01*
X307639D01*
X311062Y302658D01*
X335349D01*
X337752Y300255D01*
X340595D01*
X348821Y292029D01*
X370969D01*
X392040Y313100D01*
Y316379D01*
X404606Y328945D01*
X434323D01*
X485050Y379672D01*
Y383194D01*
X498547Y396691D01*
X555162D01*
X580519Y422048D01*
X580520D01*
Y425520D01*
X600920Y445920D01*
Y467073D01*
X622600Y488753D01*
G01X716260Y525295D02*
X712868Y521903D01*
X700199D01*
X699220Y520924D01*
X637956D01*
X633224Y516192D01*
X629416D01*
X580640Y467416D01*
Y447562D01*
X559844Y426766D01*
X553951D01*
X540163Y412978D01*
X492408D01*
X427666Y348236D01*
X389122D01*
X381886Y341000D01*
X351144D01*
X347130Y345014D01*
Y345478D01*
X336398Y356210D01*
X322252D01*
X322047Y356005D01*
X320486D01*
X320390Y356101D01*
X289882D01*
X288510Y354729D01*
X273970D01*
X270473Y351232D01*
X234062D01*
X230361Y354933D01*
X224175D01*
X222974Y356134D01*
G01X212635Y665604D02*
X214929Y663310D01*
X251141D01*
X266385Y648066D01*
X279443D01*
X295472Y632037D01*
X316320D01*
X317278Y631079D01*
X355477D01*
X356890Y632492D01*
X381170D01*
X384108Y635430D01*
X403554D01*
X404300Y636176D01*
X407900D01*
X409797Y634279D01*
X440789D01*
X443089Y636579D01*
X463793D01*
X466675Y633697D01*
X485624D01*
X494621Y624700D01*
X500300D01*
X501100Y625500D01*
X513700D01*
X520424Y632224D01*
X531115D01*
X532479Y633588D01*
G01X265550Y668415D02*
X263410Y670555D01*
Y679323D01*
X226254Y716479D01*
X226250D01*
X226110Y716619D01*
Y718270D01*
X224410Y719970D01*
G01X275710Y681593D02*
Y681751D01*
X239146Y718315D01*
X238495D01*
X237485Y719325D01*
Y724220D01*
X235655Y726050D01*
X233561D01*
X225940Y733671D01*
G01Y736437D02*
X224215Y734712D01*
Y732912D01*
X232170Y724957D01*
Y721094D01*
X240073Y713191D01*
Y711432D01*
X250900Y700605D01*
X253362D01*
X272030Y681937D01*
Y671133D01*
X265658Y664761D01*
X261890D01*
G01X376600Y408045D02*
X375670D01*
X371505Y403880D01*
X294301D01*
X289985Y399564D01*
X260503D01*
X254124Y393185D01*
X242489D01*
X241451Y392147D01*
G01X508400Y617803D02*
X506047D01*
X505700Y618150D01*
X489485D01*
X480080Y627555D01*
X474650D01*
X473428Y628777D01*
X462727D01*
X459199Y632305D01*
X443163D01*
X440006Y629148D01*
X407026D01*
X406048Y630126D01*
X405380D01*
X404855Y630651D01*
X389122D01*
X386373Y627902D01*
X358854D01*
X358376Y627424D01*
X317557D01*
X315630Y625497D01*
X313052D01*
X310250Y628299D01*
X294038D01*
X278870Y643467D01*
Y643470D01*
X277924Y644416D01*
X264860D01*
X258269Y651007D01*
X243921D01*
X240291Y647377D01*
X237412D01*
X234480Y644445D01*
Y637705D01*
X234500Y637685D01*
G01X227650Y720791D02*
Y717051D01*
X250620Y694082D01*
X254120D01*
X265683Y682519D01*
X267240D01*
G01X269420Y677062D02*
Y682779D01*
X267453Y684746D01*
X265900D01*
X254906Y695740D01*
X250730D01*
X249726Y696744D01*
Y698602D01*
X235988Y712339D01*
X234245D01*
X230440Y716144D01*
Y724242D01*
G01X444700Y651900D02*
X437500D01*
X436355Y650755D01*
X433037D01*
X432239Y649957D01*
X413494D01*
X412363Y651088D01*
X410200D01*
X409007Y649895D01*
X384005D01*
X373892Y639782D01*
X358255D01*
X357754Y640283D01*
X345314D01*
X343120Y638089D01*
Y636909D01*
X341490Y635279D01*
X323431D01*
X316665Y642045D01*
Y642782D01*
X315655Y643792D01*
X313880D01*
X311938Y645735D01*
X294429D01*
X278344Y661820D01*
X262391D01*
X260165Y664046D01*
Y665481D01*
X260160D01*
Y680133D01*
X236120Y704173D01*
G01X266170Y694826D02*
X264414D01*
X240940Y718300D01*
Y722538D01*
X234940Y728538D01*
Y733355D01*
G01X274360Y673831D02*
X277924Y677395D01*
Y685093D01*
X271870Y691147D01*
Y691748D01*
X266470Y697148D01*
X263860D01*
X242190Y718818D01*
Y723932D01*
X236670Y729452D01*
Y734065D01*
X234940Y735795D01*
Y736392D01*
G01X279843Y675688D02*
Y686357D01*
X280075Y686589D01*
Y688070D01*
X274843Y693302D01*
Y693997D01*
X269579Y699261D01*
X265730D01*
X261490Y703501D01*
Y705258D01*
X256092Y710656D01*
X253450D01*
X245555Y718551D01*
Y723868D01*
X245625Y723938D01*
Y726285D01*
X242117Y729793D01*
Y730906D01*
X239500Y733523D01*
G01X630420Y491511D02*
X628617D01*
X601970Y464864D01*
Y445485D01*
X581570Y425085D01*
Y421613D01*
X555182Y395225D01*
X498574D01*
X486108Y382759D01*
Y378805D01*
X435198Y327895D01*
X405338D01*
X394430Y316987D01*
Y314004D01*
X371405Y290979D01*
X348381D01*
X340155Y299205D01*
X337317D01*
X334914Y301608D01*
X302956D01*
X302065Y302499D01*
X288911D01*
X274643Y288231D01*
X267535D01*
X265914Y289852D01*
X262212D01*
X260671Y288311D01*
Y279730D01*
X258373Y277432D01*
X250622D01*
X244664Y271474D01*
Y261864D01*
X247389Y259139D01*
G01X565310Y412700D02*
Y412358D01*
X553543Y400591D01*
X496919D01*
X431833Y335505D01*
X405516D01*
X378187Y308176D01*
X368790D01*
X360684Y300070D01*
X350412D01*
X345500Y304982D01*
Y306438D01*
X343106Y308832D01*
X335972D01*
X334139Y310665D01*
X311107D01*
X307269Y314503D01*
X260016D01*
X254631Y319888D01*
Y324716D01*
G01X273510Y699749D02*
Y704343D01*
X260121Y717732D01*
X249910D01*
X248530Y719112D01*
Y721829D01*
G01X250630Y719457D02*
X261917D01*
X276281Y705093D01*
X278370D01*
G01X289365Y673719D02*
X281330Y681754D01*
Y688590D01*
X276100Y693820D01*
Y694515D01*
X276096D01*
X266755Y703856D01*
X265590D01*
X256670Y712776D01*
Y713096D01*
X255660Y714106D01*
X255340D01*
X255256Y714190D01*
X251684D01*
X246805Y719069D01*
Y723350D01*
X246875Y723420D01*
Y726946D01*
X243940Y729881D01*
Y736412D01*
G01X293068Y677108D02*
X291240Y678936D01*
Y689547D01*
X280100Y700687D01*
Y705803D01*
X265196Y720707D01*
X264539D01*
X261480Y723766D01*
Y725027D01*
X252940Y733567D01*
G01X269380Y302736D02*
Y303181D01*
X271793Y305594D01*
X283609D01*
X290782Y312767D01*
X306662D01*
X312458Y306971D01*
X338069D01*
X339780Y305260D01*
X342882D01*
X351766Y296376D01*
X359356D01*
X366182Y303202D01*
X367220D01*
G01X265318Y326487D02*
X265757Y326048D01*
Y325664D01*
X272379Y319042D01*
X372065D01*
X381523Y328500D01*
X391751D01*
X403006Y339755D01*
X430044D01*
X495294Y405005D01*
X543701D01*
X557587Y418891D01*
X563395D01*
X592825Y448321D01*
Y453971D01*
X590720Y456076D01*
G01X267030Y330147D02*
X266318Y330859D01*
Y340291D01*
X268583Y342556D01*
X270021D01*
X276004Y348539D01*
X286995D01*
X288972Y346562D01*
X296378D01*
X299921Y350105D01*
X314548D01*
X316346Y348307D01*
X321276D01*
X322114Y347469D01*
X338859D01*
X348928Y337400D01*
X383686D01*
X391522Y345236D01*
X428924D01*
X493666Y409978D01*
X541419D01*
X555207Y423766D01*
X561095D01*
X583650Y446321D01*
Y462263D01*
X630892Y509505D01*
X632872D01*
X638372Y515005D01*
X642560D01*
X643435Y515880D01*
X669290D01*
X670161Y515009D01*
X695386D01*
X695779Y515402D01*
X698093D01*
X707920Y505575D01*
G01X603819Y485332D02*
X581695Y463208D01*
Y447132D01*
X560279Y425716D01*
X554390D01*
X540602Y411928D01*
X492852D01*
X428110Y347186D01*
X390240D01*
X382454Y339400D01*
X349899D01*
X339463Y349836D01*
X336641D01*
X334630Y351847D01*
X327660D01*
X327406Y352101D01*
X296961D01*
X295563Y350703D01*
X273587D01*
X271366Y348482D01*
X268861D01*
X260754Y340375D01*
Y336018D01*
X262247Y334525D01*
Y334502D01*
G01X266882Y388165D02*
X267211Y388494D01*
X286156D01*
X286745Y387905D01*
X298463D01*
X300473Y389915D01*
X323868D01*
X328150Y385633D01*
X336581D01*
X344350Y393402D01*
X361531D01*
X363154Y395025D01*
X367877D01*
X369500Y393402D01*
X381100D01*
X382620Y391882D01*
G01X264421Y384812D02*
X264494D01*
X267719Y381587D01*
X334875D01*
X345040Y391752D01*
X362220D01*
X363466Y392998D01*
X367564D01*
X368810Y391752D01*
X378515D01*
X382190Y388077D01*
G01X318950Y432473D02*
X317146Y434277D01*
X296705D01*
X282982Y420554D01*
X267626D01*
X265532Y422648D01*
G01X501120Y633249D02*
Y632820D01*
X498000Y629700D01*
X494200D01*
X485535Y638365D01*
X476635D01*
X473941Y641059D01*
X467800D01*
X465841Y639100D01*
X452100D01*
X449600Y641600D01*
X443300D01*
X439500Y637800D01*
X423600D01*
X418815Y642585D01*
X407422D01*
X405476Y640639D01*
X402916D01*
X400350Y643205D01*
X398500D01*
X396591Y645114D01*
X393660D01*
X392526Y643980D01*
X382556D01*
X375568Y636992D01*
X351745D01*
X347932Y633179D01*
X321848D01*
X316820Y638207D01*
X306729D01*
X303830Y641106D01*
X298646D01*
X297880Y640340D01*
X292796D01*
X285220Y647916D01*
Y649880D01*
X281535Y653565D01*
X267216D01*
X266610Y654171D01*
G01X270040Y651241D02*
X270819Y652020D01*
X281595D01*
X284148Y649467D01*
Y647503D01*
X294494Y637157D01*
X316270D01*
X321298Y632129D01*
X348367D01*
X352180Y635942D01*
X376124D01*
X382174Y641992D01*
X392556D01*
X394959Y639589D01*
X406471D01*
X408417Y641535D01*
X418139D01*
X423274Y636400D01*
X439800D01*
X443900Y640500D01*
X447749D01*
X450449Y637800D01*
X465400D01*
X467400Y635800D01*
X472200D01*
X473547Y637147D01*
X484653D01*
X496000Y625800D01*
X499500D01*
X508000Y634300D01*
X510700D01*
G01X496690Y633589D02*
Y636409D01*
X490473Y642626D01*
X484510D01*
X482944Y644192D01*
X481200D01*
X480092Y645300D01*
X461761D01*
X459620Y643159D01*
X456052D01*
X452411Y646800D01*
X442547D01*
X436661Y640914D01*
X425657D01*
X417871Y648700D01*
X412900D01*
X411630Y647430D01*
X383308D01*
X374100Y638222D01*
X351480D01*
X347487Y634229D01*
X322489D01*
X317461Y639257D01*
X315310D01*
X313210Y641357D01*
Y642134D01*
X310721Y644623D01*
X289998D01*
X286270Y648351D01*
Y650315D01*
X281819Y654766D01*
X270164D01*
X269640Y655290D01*
G01X301070Y655920D02*
X299742Y654592D01*
X292177D01*
X291125Y655644D01*
Y659650D01*
X292340Y660865D01*
Y669058D01*
X296043Y672761D01*
Y686982D01*
X294220Y688805D01*
Y690660D01*
X282690Y702190D01*
Y706936D01*
X272940Y716686D01*
Y718710D01*
X271925Y719725D01*
X270855D01*
X269215Y721365D01*
Y736357D01*
X280351Y747493D01*
X284532D01*
G01X293440Y748380D02*
X283733Y738673D01*
X279491D01*
X277165Y736347D01*
Y730505D01*
X272670Y726010D01*
Y720755D01*
X275040Y718385D01*
Y716362D01*
X277108Y714294D01*
X280146D01*
X289502Y704938D01*
Y700351D01*
X297675Y692178D01*
Y687121D01*
X299500Y685296D01*
Y674005D01*
X296620Y671125D01*
Y667358D01*
X294090Y664828D01*
Y660545D01*
X292850Y659305D01*
Y656359D01*
G01X320360Y642275D02*
Y643649D01*
X314898Y649184D01*
X295165D01*
X288990Y655359D01*
Y659283D01*
X291090Y661383D01*
Y672690D01*
X294793Y676393D01*
Y686461D01*
X292970Y688284D01*
Y690139D01*
X281430Y701679D01*
Y706428D01*
X271210Y716648D01*
Y718000D01*
G01X295890Y662662D02*
Y664851D01*
X300750Y669711D01*
Y691326D01*
X291561Y700515D01*
Y704647D01*
X280664Y715544D01*
X277626D01*
X276616Y716554D01*
Y718577D01*
X274155Y721038D01*
Y725727D01*
X278420Y729992D01*
Y735455D01*
X280388Y737423D01*
X287821D01*
X288220Y737822D01*
X292384D01*
X295110Y735096D01*
Y733723D01*
X295700Y733133D01*
G01X654240Y511568D02*
X650209Y507537D01*
X643100D01*
X629813Y494250D01*
X625339D01*
X598970Y467881D01*
Y446728D01*
X578570Y426328D01*
Y422857D01*
X554354Y398641D01*
X497730D01*
X432644Y333555D01*
X406333D01*
X388980Y316202D01*
Y313079D01*
X370327Y294426D01*
X350953D01*
X342464Y302915D01*
X338727D01*
X336621Y305021D01*
X311639D01*
X310303Y306357D01*
X309506D01*
X308246Y307617D01*
X299797D01*
X295811Y311603D01*
X292605D01*
X282002Y301000D01*
X278318D01*
X277020Y302298D01*
G01X591100Y450128D02*
Y448081D01*
X563181Y420162D01*
X557287D01*
X543401Y406276D01*
X495080D01*
X429830Y341026D01*
X402476D01*
X391000Y329550D01*
X380775D01*
X371317Y320092D01*
X326193D01*
X322632Y323653D01*
X306931D01*
X306724Y323446D01*
X290363D01*
X288466Y325343D01*
G01X303759Y331478D02*
X302272D01*
X289939Y343811D01*
X275602D01*
G01X395740Y407528D02*
X395528Y407316D01*
X387647D01*
X382489Y402158D01*
X300748D01*
X288220Y389630D01*
G01X393370Y411618D02*
X392525Y410773D01*
X378318D01*
X377315Y409770D01*
X373015D01*
X368775Y405530D01*
X293014D01*
X289842Y402358D01*
X287067D01*
G01X289365Y665845D02*
X287446Y663926D01*
Y654852D01*
X295246Y647052D01*
X313880D01*
X317720Y643212D01*
Y642475D01*
X323866Y636329D01*
X341055D01*
X342070Y637344D01*
Y639125D01*
X346955Y644010D01*
X350560D01*
X351120Y643450D01*
X376073D01*
X383818Y651195D01*
X396970D01*
X399363Y653588D01*
G01X295950Y689520D02*
Y691243D01*
X285073Y702120D01*
Y706709D01*
X284760Y707022D01*
G01X289060Y722193D02*
X287080Y724173D01*
Y726882D01*
X285626Y728336D01*
X279080D01*
X277610Y726866D01*
Y722719D01*
X281238Y719091D01*
X283662D01*
X296425Y706328D01*
X300169D01*
X303860Y702637D01*
Y668343D01*
X300880Y665363D01*
Y664296D01*
G01X281830Y722184D02*
Y721466D01*
X282955Y720341D01*
X284180D01*
X287994Y716527D01*
X291196D01*
X295375Y712348D01*
X296901D01*
X308110Y701139D01*
Y665981D01*
X307010Y664881D01*
X305570D01*
X304569Y663880D01*
Y661871D01*
X302772Y660074D01*
Y659604D01*
G01X301360Y652183D02*
X303140Y653963D01*
Y656789D01*
X301040Y658889D01*
Y660276D01*
X298530Y662786D01*
Y664781D01*
X302210Y668461D01*
Y691810D01*
X299580Y694440D01*
Y702269D01*
X297580Y704269D01*
X295294D01*
X285130Y714433D01*
G01X316165Y693404D02*
X310810Y698759D01*
Y703155D01*
X301956Y712009D01*
Y715428D01*
X296715Y720669D01*
X291271D01*
X289150Y718548D01*
G01X280210Y734805D02*
X284047Y730968D01*
X290333D01*
X296210Y725091D01*
Y723667D01*
X303731Y716146D01*
X304396D01*
X305406Y715136D01*
Y713744D01*
X305388Y713726D01*
Y712288D01*
X313486Y704190D01*
X313945D01*
X315370Y702765D01*
Y697473D01*
X319150Y693693D01*
Y649109D01*
X328710Y639549D01*
Y638794D01*
X329725Y637779D01*
X337530D01*
X338800Y639049D01*
Y640166D01*
X340290Y641656D01*
Y644448D01*
X340669Y644827D01*
G01X288390Y734796D02*
X289293Y733893D01*
X291144D01*
X297879Y727158D01*
X300888D01*
X310260Y717786D01*
Y716891D01*
X312033Y715118D01*
X312987D01*
X315110Y712995D01*
Y710115D01*
X316620Y708605D01*
Y698440D01*
X320400Y694660D01*
Y655068D01*
X332710Y642758D01*
Y642694D01*
G01X298452Y340487D02*
X302517Y344552D01*
X307495D01*
X308795Y345852D01*
X310225D01*
X311426Y344651D01*
X322669D01*
X323362Y345344D01*
X338076D01*
X348020Y335400D01*
X385104D01*
X392990Y343286D01*
X429732D01*
X494373Y407927D01*
X542718D01*
X556603Y421812D01*
X556918D01*
X556922Y421816D01*
X562501D01*
X585600Y444915D01*
Y461455D01*
X631700Y507555D01*
X633690D01*
X636755Y510620D01*
X649590D01*
X652488Y513518D01*
X655057D01*
X657270Y511305D01*
X690555D01*
X694810Y507050D01*
Y501392D01*
X696991Y499211D01*
Y486808D01*
X698117Y485682D01*
X707619D01*
X708690Y484611D01*
Y478050D01*
X710768Y475972D01*
G01X372080Y330574D02*
X366431D01*
X363267Y327410D01*
X355610D01*
X350860Y332160D01*
X348439D01*
X337205Y343394D01*
X325989D01*
X322937Y340342D01*
X315972D01*
X309950Y334320D01*
X306601D01*
X303759Y331478D01*
G01X293290Y389737D02*
X297841D01*
X301164Y393060D01*
X327587D01*
X334835Y400308D01*
X385323D01*
X389740Y404725D01*
G01X314614Y690767D02*
X309560Y695821D01*
Y702001D01*
X297763Y713798D01*
X296508D01*
X293887Y716419D01*
Y718357D01*
X293300Y718944D01*
G01X302810Y733807D02*
X311150Y725467D01*
Y722918D01*
X315120Y718948D01*
Y718268D01*
X319820Y713568D01*
Y705823D01*
X321835Y703808D01*
Y702378D01*
X320715Y701258D01*
Y698855D01*
X322900Y696670D01*
Y660517D01*
X329265Y654152D01*
Y652132D01*
X335685Y645712D01*
Y641460D01*
X333766Y639541D01*
X330477D01*
X330440Y639504D01*
G01X298590Y733669D02*
X302155Y730104D01*
X304448D01*
X309590Y724962D01*
Y722709D01*
X313868Y718431D01*
Y717654D01*
X316360Y715161D01*
Y711408D01*
X318110Y709658D01*
Y699689D01*
X321650Y696149D01*
Y656199D01*
X334435Y643414D01*
Y641978D01*
X333284Y640827D01*
X331581D01*
X329734Y642674D01*
X328032D01*
G01X317492Y618193D02*
Y622172D01*
X319617Y624297D01*
X328327D01*
X329110Y623514D01*
G01X337070Y639759D02*
Y646100D01*
X334870Y648300D01*
Y656472D01*
X333885Y657457D01*
Y658897D01*
X333915Y658927D01*
Y660953D01*
X331455Y663413D01*
Y665768D01*
X324159Y673064D01*
Y676159D01*
X327095Y679095D01*
Y706121D01*
X323650Y709566D01*
Y716366D01*
X318282Y721734D01*
X314107D01*
X312635Y723206D01*
Y727419D01*
X307280Y732774D01*
Y733705D01*
G01X330410Y712895D02*
X325809Y717496D01*
X324571D01*
X317534Y724533D01*
X314930D01*
G01X336720Y310846D02*
X343858D01*
X350235Y304469D01*
X362322D01*
X368977Y311124D01*
X376215D01*
X384248Y319157D01*
G01X352940Y518025D02*
Y518031D01*
X352706Y518265D01*
X350022D01*
X346317Y514560D01*
X346254D01*
X337280Y505586D01*
Y490682D01*
X341500Y486462D01*
Y474676D01*
X350180Y465996D01*
Y447992D01*
X352847Y445325D01*
X354750D01*
G01X504980Y616425D02*
X489071D01*
X478991Y626505D01*
X474210D01*
X472990Y627725D01*
Y627727D01*
X462290D01*
X461758Y628259D01*
X461756D01*
X458760Y631255D01*
X444087D01*
X440930Y628098D01*
X406590D01*
X406166Y628522D01*
X406162D01*
X405608Y629076D01*
X404940D01*
X404420Y629596D01*
Y629601D01*
X389566D01*
X386817Y626852D01*
X359295D01*
X358820Y626377D01*
Y626374D01*
X331970D01*
X329110Y623514D01*
G01X340340Y638054D02*
Y639655D01*
X342394Y641709D01*
Y648829D01*
X337450Y653773D01*
Y659715D01*
X337115Y660050D01*
Y671199D01*
X329795Y678519D01*
Y708200D01*
X332135Y710540D01*
Y721738D01*
X329590Y724283D01*
G01X335390Y667895D02*
X335154D01*
X326890Y676159D01*
G01X339300Y716800D02*
X335040Y712540D01*
Y709333D01*
X334445Y708738D01*
Y694714D01*
X334385Y694654D01*
Y684344D01*
X340530Y678199D01*
Y675658D01*
G01X340870Y665042D02*
X342859Y667031D01*
Y679220D01*
X336073Y686006D01*
Y689154D01*
X341475Y694556D01*
Y701301D01*
X340505Y702271D01*
Y711694D01*
X341190Y712379D01*
G01X338460Y724585D02*
Y721215D01*
X342155Y717520D01*
Y715789D01*
X336290Y709924D01*
Y698114D01*
X336110Y697934D01*
Y693934D01*
G01X331520Y701642D02*
Y707869D01*
X333585Y709934D01*
Y722728D01*
X330305Y726008D01*
X323043D01*
X321930Y724895D01*
G01X353060Y61504D02*
X353529Y61973D01*
X359601D01*
X365844Y68216D01*
X376660D01*
X378310Y69866D01*
X385756D01*
X387406Y68216D01*
X396739D01*
X397070Y67885D01*
X398879D01*
X400439Y69445D01*
X411543D01*
X432850Y90752D01*
Y108326D01*
X437330Y112806D01*
Y123208D01*
X450910Y136788D01*
X453990D01*
X469198Y151996D01*
Y197188D01*
X468452Y197934D01*
G01X678450Y508438D02*
X660970D01*
X652866Y500334D01*
X649451D01*
X636336Y487219D01*
X627412D01*
X604070Y463877D01*
Y444615D01*
X583670Y424215D01*
Y420199D01*
X556596Y393125D01*
X512144D01*
X437793Y318774D01*
X416680D01*
X381030Y283124D01*
X344580D01*
X341694Y286010D01*
X341693D01*
G01X352420Y375672D02*
X354428Y373664D01*
X368575D01*
X369984Y372257D01*
X379720D01*
G01X379300Y380862D02*
X370578D01*
X370066Y381374D01*
X344562D01*
X343770Y382166D01*
G01X350690Y516376D02*
X347762Y513448D01*
X346984D01*
X338840Y505304D01*
Y491752D01*
X343210Y487382D01*
Y476600D01*
X352639Y467171D01*
X381239D01*
G01X357610Y748302D02*
Y749412D01*
X356099Y750923D01*
X353481D01*
X339995Y737437D01*
Y730756D01*
X345455Y725296D01*
Y722946D01*
X348000Y720401D01*
Y716110D01*
X349010Y715100D01*
Y711598D01*
X348835Y711423D01*
Y679330D01*
X355627Y672538D01*
Y664907D01*
X352445Y661725D01*
X351688D01*
X345056Y655093D01*
X340630D01*
G01X409010Y726147D02*
X408923Y726060D01*
Y722713D01*
X400815Y714605D01*
Y700238D01*
X399460Y698883D01*
X391606D01*
X390180Y697457D01*
Y692251D01*
X392820Y689610D01*
Y683527D01*
X392110Y682817D01*
Y680789D01*
X380370Y669049D01*
X377872D01*
X371955Y663132D01*
Y655473D01*
X370857Y654375D01*
X366634D01*
X365700Y653441D01*
X364265D01*
X362867Y654839D01*
X355896D01*
X353192Y652135D01*
X341148D01*
X338905Y654378D01*
Y657749D01*
X341660Y660504D01*
Y661929D01*
X340645Y662944D01*
X340528D01*
X339145Y664327D01*
Y670601D01*
X338970Y670776D01*
G01X351720Y670018D02*
X350057Y671681D01*
Y676333D01*
X347585Y678805D01*
Y711941D01*
X347760Y712116D01*
Y714582D01*
X346750Y715592D01*
Y719121D01*
X338270Y727601D01*
Y733387D01*
G01X365620Y663069D02*
X361792D01*
X356880Y667981D01*
Y676590D01*
X350085Y683385D01*
Y710905D01*
X350260Y711080D01*
Y715618D01*
X349250Y716628D01*
Y721541D01*
X347600Y723191D01*
Y724927D01*
X342630Y729897D01*
Y737632D01*
X350720Y745722D01*
G01X337798Y686721D02*
X345520Y694443D01*
Y711644D01*
X346510Y712634D01*
Y714064D01*
X345500Y715074D01*
Y717666D01*
X342230Y720936D01*
G01X354420Y749198D02*
X353491Y748269D01*
Y745611D01*
X343880Y736000D01*
Y731855D01*
X348855Y726879D01*
Y723712D01*
X350500Y722067D01*
Y719638D01*
X353820Y716318D01*
Y695799D01*
X356010Y693609D01*
Y680038D01*
X358130Y677918D01*
Y669905D01*
X361182Y666853D01*
X362888D01*
X364947Y664794D01*
X366340D01*
X367580Y663554D01*
Y660291D01*
X369590Y658281D01*
Y656858D01*
X368580Y655848D01*
X365562D01*
X364980Y655266D01*
G01X364115Y692990D02*
X361415D01*
X356320Y698085D01*
Y717357D01*
X356105Y717572D01*
Y719397D01*
X359448Y722740D01*
X362109D01*
X366475Y727106D01*
Y728536D01*
X365465Y729546D01*
X361422D01*
X358852Y726976D01*
X352616D01*
X345610Y733982D01*
G01X472670Y166398D02*
Y158394D01*
X470860Y156584D01*
Y151321D01*
X454677Y135138D01*
X451594D01*
X438980Y122524D01*
Y110805D01*
X434500Y106325D01*
Y90068D01*
X412108Y67676D01*
X401011D01*
X399570Y66235D01*
X396381D01*
X396050Y66566D01*
X386600D01*
X384950Y68216D01*
X380069D01*
X378419Y66566D01*
X367778D01*
X365670Y64458D01*
G01X379286Y378015D02*
X371084D01*
X369538Y379561D01*
X357881D01*
X355320Y377000D01*
X354690D01*
G01X364645Y377065D02*
X369455D01*
X371565Y374955D01*
X379560D01*
G01X364880Y384455D02*
X365408Y383927D01*
X379712D01*
X379750Y383965D01*
G01X365990Y645272D02*
X366874Y646156D01*
X372574D01*
X398275Y671857D01*
Y689301D01*
X398104Y689472D01*
Y691296D01*
X405750Y698942D01*
Y705372D01*
X411306Y710928D01*
Y715820D01*
X415805Y720319D01*
Y722394D01*
X420894Y727483D01*
X424968D01*
X433710Y736225D01*
Y736638D01*
X439165Y742093D01*
X627019D01*
X630040Y745114D01*
G01X367870Y650239D02*
X375172D01*
X394820Y669887D01*
Y680981D01*
X395500Y681661D01*
Y692868D01*
X403073Y700441D01*
Y708229D01*
X404265Y709421D01*
Y715444D01*
X419056Y730235D01*
X422166D01*
X423056Y731125D01*
X424869D01*
X428160Y734416D01*
Y737040D01*
X435625Y744505D01*
X625146D01*
X628530Y747889D01*
X631190D01*
X632820Y746259D01*
Y737770D01*
X635460Y735130D01*
G01X363340Y650512D02*
X364233Y651405D01*
X366256D01*
X366986Y652135D01*
X370668D01*
X373410Y654877D01*
Y657664D01*
X390372Y674626D01*
Y676946D01*
X393620Y680194D01*
Y682276D01*
X394270Y682926D01*
Y694382D01*
X391910Y696742D01*
G01X361810Y675011D02*
X363430Y673391D01*
Y672207D01*
X363600Y672037D01*
Y668312D01*
X365504Y666408D01*
X368820D01*
X369825Y667413D01*
Y669544D01*
X375220Y674939D01*
Y705048D01*
X373965Y706303D01*
Y712181D01*
X383035Y721251D01*
X397587D01*
X400015Y723679D01*
X402646D01*
X412215Y733248D01*
Y741690D01*
X415780Y745255D01*
Y747078D01*
G01X375548Y731459D02*
X373910Y729821D01*
Y717776D01*
X369390Y713256D01*
Y709106D01*
X373970Y704526D01*
Y676865D01*
X369930Y672825D01*
Y671417D01*
X368920Y670407D01*
X366815D01*
X365380Y668972D01*
G01X365160Y672922D02*
Y674413D01*
X363360Y676213D01*
Y676227D01*
X359090Y680497D01*
Y689113D01*
X361242Y691265D01*
X364830D01*
X365840Y692275D01*
Y693705D01*
X362692Y696853D01*
X361621D01*
X357830Y700644D01*
Y718682D01*
G01X361760Y668716D02*
X359380Y671096D01*
Y678436D01*
X357840Y679976D01*
Y693835D01*
X355070Y696605D01*
Y716839D01*
X354855Y717054D01*
Y719973D01*
X362703Y727821D01*
X364750D01*
G01X364320Y680434D02*
Y680788D01*
X366359Y682827D01*
X368020D01*
X372720Y687527D01*
Y702374D01*
X365625Y709469D01*
Y716628D01*
X371620Y722623D01*
Y740246D01*
X375900Y744526D01*
Y749038D01*
X373784Y751154D01*
X366679D01*
X364090Y748565D01*
G01X364649Y684022D02*
Y684342D01*
X366821Y686514D01*
X368608D01*
X371470Y689376D01*
Y700200D01*
X368226Y703444D01*
X366765D01*
X365755Y704454D01*
Y706389D01*
X364375Y707770D01*
Y708944D01*
X364370Y708949D01*
Y717146D01*
X370290Y723066D01*
Y744976D01*
X373500Y748186D01*
Y748457D01*
G01X354060Y734790D02*
X355099Y733751D01*
Y732533D01*
X356381Y731251D01*
X358237D01*
X360162Y733176D01*
X365702D01*
X365710Y733184D01*
X367150D01*
X367158Y733176D01*
X367646D01*
X368930Y731892D01*
Y723474D01*
X363120Y717664D01*
Y716580D01*
X359760Y713220D01*
Y710611D01*
X364500Y705871D01*
Y703933D01*
X365320Y703113D01*
Y700297D01*
X370220Y695397D01*
Y689894D01*
X368289Y687963D01*
X364765D01*
G01X383247Y64141D02*
X384298Y63090D01*
X393069D01*
X396577Y59582D01*
X409290D01*
X437800Y88092D01*
Y103823D01*
X448210Y114233D01*
Y123074D01*
X478188Y153052D01*
Y169749D01*
X475813Y172124D01*
X473950D01*
G01X373560Y63973D02*
X374501Y64914D01*
X379108D01*
X380760Y66566D01*
X384252D01*
X385903Y64915D01*
X395360D01*
X395690Y64585D01*
X397658D01*
X398922Y63321D01*
X410087D01*
X436150Y89384D01*
Y104731D01*
X446560Y115141D01*
Y123758D01*
X476538Y153736D01*
Y166499D01*
X475760Y167277D01*
Y168747D01*
G01X383750Y437058D02*
X391930D01*
X393059Y435929D01*
X466073D01*
X479250Y449106D01*
Y454180D01*
X485900Y460830D01*
Y466296D01*
X487170Y467566D01*
Y503429D01*
X504066Y520325D01*
X505328D01*
X507620Y522617D01*
X571854D01*
X599318Y550081D01*
Y588194D01*
X605290Y594166D01*
G01X389690Y60665D02*
Y60019D01*
X391916Y57793D01*
X410159D01*
X440110Y87744D01*
Y103799D01*
X455050Y118739D01*
Y125146D01*
X479838Y149934D01*
Y170433D01*
X475428Y174843D01*
X474630D01*
G01X636170Y493028D02*
X632150Y489008D01*
X627716D01*
X603020Y464312D01*
Y445050D01*
X582620Y424650D01*
Y420634D01*
X556161Y394175D01*
X500279D01*
X487510Y381406D01*
Y378722D01*
X435281Y326493D01*
X406805D01*
X399880Y319568D01*
G01X399363Y653588D02*
X409180D01*
X410274Y654682D01*
X411704D01*
X415379Y651007D01*
X422722D01*
X424195Y652480D01*
X436080D01*
X437500Y653900D01*
X449000D01*
X449400Y653500D01*
Y653480D01*
X450400Y652480D01*
X466670D01*
X468095Y653905D01*
X469525D01*
X470318Y653112D01*
X485234D01*
X494025Y661903D01*
X496340D01*
X496398Y661845D01*
X515541D01*
G01X633970Y723033D02*
Y725332D01*
X633415Y725887D01*
Y734995D01*
X631765Y736645D01*
Y745829D01*
X630755Y746839D01*
X628972D01*
X625588Y743455D01*
X436060D01*
X429210Y736605D01*
Y733981D01*
X425304Y730075D01*
X423730D01*
X422188Y728533D01*
X418839D01*
X406320Y716014D01*
Y708930D01*
X404700Y707310D01*
Y699992D01*
X396550Y691842D01*
Y680266D01*
G01X400730Y721954D02*
X398620Y719844D01*
Y701411D01*
G01X631690Y733744D02*
Y734606D01*
X625532Y740764D01*
X442716D01*
X429568Y727616D01*
X427376D01*
X424670Y724910D01*
Y723092D01*
X422769Y721191D01*
X418661D01*
X413860Y716390D01*
Y711993D01*
X406800Y704933D01*
Y698486D01*
X404313Y695999D01*
Y668337D01*
X407105Y665545D01*
X411850D01*
X412250Y665945D01*
X421080D01*
G01X469467Y679915D02*
X443722D01*
X441238Y677431D01*
X435149D01*
X433455Y675737D01*
X431508D01*
X431470Y675775D01*
X429359D01*
X417108Y688027D01*
X411862D01*
G01X412878Y693183D02*
X410137Y690442D01*
Y687312D01*
X411147Y686302D01*
X411592D01*
X414037Y683857D01*
X419178D01*
X428710Y674325D01*
X430862D01*
X431284Y673903D01*
X442555D01*
X445704Y677052D01*
X469421D01*
X469977Y676496D01*
G01X424200Y733399D02*
X423271D01*
X421557Y731685D01*
X417895D01*
X412555Y726345D01*
X409208D01*
X409010Y726147D01*
G01X440688Y694438D02*
X433695Y701431D01*
X429952D01*
X425140Y706243D01*
Y708817D01*
X417330Y716627D01*
Y717420D01*
G01X440690Y702386D02*
X432463Y710613D01*
Y711871D01*
X427130Y717204D01*
Y717871D01*
G01X421730Y717398D02*
X429858Y709270D01*
X431057D01*
X442413Y697914D01*
Y691163D01*
X440688Y689438D01*
G01X427230Y707377D02*
X426550Y708057D01*
Y709516D01*
X420005Y716061D01*
Y718113D01*
X421015Y719123D01*
X423716D01*
X424410Y718429D01*
G01X440660Y712065D02*
X428485Y724240D01*
X426440D01*
G01X431440Y723955D02*
X436222Y719172D01*
Y719138D01*
X452369Y702991D01*
X477939D01*
X484424Y696506D01*
X496275D01*
X498370Y694411D01*
Y682242D01*
X496277Y680149D01*
Y678185D01*
G01X439670Y70044D02*
Y80802D01*
X443050Y84182D01*
Y102580D01*
X481488Y141018D01*
Y171415D01*
X475044Y177859D01*
X473580D01*
G01X459108Y253181D02*
X456625D01*
X446100Y263706D01*
Y280667D01*
X443590Y283177D01*
Y321804D01*
X512960Y391174D01*
X557403D01*
X585629Y419400D01*
Y423416D01*
X607645Y445432D01*
Y463884D01*
X629030Y485269D01*
X637146D01*
X641538Y489661D01*
X651351D01*
X656277Y494587D01*
X661233D01*
X664347Y491473D01*
X679299D01*
G01X687049Y487660D02*
X686079D01*
X684389Y489350D01*
X659170D01*
X654569Y484749D01*
X640530D01*
X639100Y483319D01*
X629838D01*
X612550Y466031D01*
Y443549D01*
X555682Y386681D01*
X511225D01*
X446230Y321686D01*
Y289543D01*
X445540Y288853D01*
G01X435420Y647117D02*
X438076D01*
X439259Y648300D01*
X452971D01*
X455010Y646261D01*
X457669D01*
X458017Y646609D01*
X459000D01*
X461691Y649300D01*
X465000D01*
X467500Y646800D01*
X472278D01*
X473178Y647700D01*
X480437D01*
X481163Y648426D01*
X493742D01*
X502800Y639368D01*
X509496D01*
X512938Y642810D01*
X521090D01*
X522381Y641519D01*
X552400D01*
Y641600D01*
X553800Y643000D01*
X570800D01*
X572281Y641519D01*
X589409D01*
X614210Y666320D01*
Y667572D01*
X660925Y714287D01*
Y732494D01*
X659300Y734119D01*
G01X654000Y736400D02*
X651160Y733560D01*
Y726829D01*
X656239Y721750D01*
Y715708D01*
X612990Y672459D01*
Y668403D01*
X610620Y666033D01*
Y664781D01*
X588808Y642969D01*
X572931D01*
X570900Y645000D01*
X553731D01*
X551700Y642969D01*
X523395D01*
X522104Y644260D01*
X512330D01*
X508888Y640818D01*
X505065D01*
X503720Y642163D01*
Y644733D01*
X496212Y652241D01*
X486419D01*
X485840Y651662D01*
X473867D01*
X472640Y650435D01*
X467065D01*
X466500Y651000D01*
X460300D01*
Y650935D01*
X459800Y650435D01*
X459781D01*
X457057Y647711D01*
X455627D01*
X453538Y649800D01*
X438313D01*
X437509Y648996D01*
G01X446260Y722014D02*
X452323Y715951D01*
X454790D01*
X455795Y714946D01*
Y713506D01*
X460207Y709094D01*
X482112D01*
X483336Y707870D01*
X491620D01*
X495498Y703992D01*
X499110D01*
X504330Y698772D01*
Y686587D01*
X504740Y686177D01*
Y682582D01*
X509075Y678247D01*
X518382D01*
G01X444530Y723917D02*
Y721231D01*
X450090Y715671D01*
Y711500D01*
X453876Y707714D01*
X481006D01*
X485978Y702742D01*
X498590D01*
X500328Y701004D01*
X500330D01*
Y701000D01*
X503080Y698250D01*
Y682875D01*
X503265Y682690D01*
Y676714D01*
X519053Y660926D01*
Y653611D01*
X515438Y649996D01*
G01X465850Y733428D02*
X464715Y734563D01*
Y736707D01*
X463485Y737937D01*
X443756D01*
X442040Y736221D01*
Y732933D01*
X438165Y729058D01*
Y723990D01*
X437475Y723300D01*
Y719653D01*
X452252Y704876D01*
X479188D01*
X486308Y697756D01*
X496800D01*
X499628Y694928D01*
X499630D01*
Y694926D01*
X499750Y694806D01*
Y681007D01*
X499765Y680992D01*
Y674188D01*
X496453Y670876D01*
G01X501540Y681970D02*
X501000Y682510D01*
Y695324D01*
X500650Y695675D01*
Y695676D01*
X499898Y696429D01*
X499075Y697253D01*
Y700487D01*
X498070Y701492D01*
X484346D01*
X479710Y706126D01*
X453567D01*
X448630Y711063D01*
Y715363D01*
X447620Y716373D01*
X443322D01*
X439200Y720495D01*
Y722093D01*
G01X515429Y692278D02*
X513907Y693800D01*
X509615Y703252D01*
X500560Y712307D01*
X498726D01*
X494087Y716947D01*
X484377D01*
X481872Y719452D01*
X453442D01*
X450790Y722104D01*
Y722471D01*
X448970Y724291D01*
Y725490D01*
X447955Y726505D01*
X443844D01*
X442120Y724781D01*
G01X456530Y256034D02*
X464794D01*
X472670Y248158D01*
Y221830D01*
X480866Y213634D01*
Y210867D01*
X488017Y203716D01*
G01X683112Y483723D02*
X671070D01*
X668958Y481611D01*
X657746D01*
X655390Y479255D01*
X648245D01*
X647096Y480404D01*
X641018D01*
X640230Y479616D01*
X630378D01*
X615550Y464788D01*
Y442306D01*
X556924Y383680D01*
X512467D01*
X453740Y324953D01*
Y299321D01*
X452055Y297636D01*
X451615D01*
X448555Y294576D01*
Y281398D01*
X454480Y275473D01*
Y258084D01*
X456530Y256034D01*
G01X704550Y444407D02*
X702188Y442045D01*
X674382D01*
X673470Y442957D01*
X660018D01*
X652199Y435138D01*
X625235D01*
X617470Y427373D01*
Y427067D01*
X563538Y373135D01*
X514528D01*
X460110Y318717D01*
Y295625D01*
X453810Y289325D01*
G01X451790Y300129D02*
Y325761D01*
X511659Y385630D01*
X556116D01*
X613600Y443114D01*
Y465596D01*
X630273Y482269D01*
X640065D01*
X640150Y482354D01*
X648657D01*
X649806Y481205D01*
X653771D01*
X660443Y487877D01*
X661873D01*
X663780Y485970D01*
X689296D01*
X690986Y487660D01*
G01X459950Y722720D02*
X463906Y726676D01*
X496049D01*
X505200Y717525D01*
Y713640D01*
X521942Y696898D01*
Y674238D01*
X517806Y670102D01*
G01X449060Y721761D02*
X452925Y717896D01*
X464660D01*
X487576Y713249D01*
X489656Y712460D01*
Y711881D01*
X500834Y704358D01*
X501694D01*
X506752Y699300D01*
X506807D01*
X508091Y698016D01*
X508134Y697905D01*
Y685176D01*
X506470Y683512D01*
G01X451320Y725044D02*
Y724168D01*
X452230Y723258D01*
Y722432D01*
X453960Y720702D01*
X473668D01*
X476990Y724024D01*
X495154D01*
X502700Y716478D01*
Y712361D01*
X514860Y700201D01*
Y697847D01*
X515429Y697278D01*
G01X453960Y723142D02*
Y723403D01*
X458483Y727926D01*
X496569D01*
X506580Y717915D01*
Y714028D01*
X523192Y697416D01*
Y670168D01*
X518800Y665776D01*
G01X476160Y734205D02*
X475887Y733932D01*
X475615D01*
X473386Y731703D01*
X457820D01*
X455410Y734113D01*
G01X505690Y654419D02*
X510367Y649742D01*
X513249D01*
X514720Y648271D01*
X516160D01*
X520776Y652887D01*
Y664312D01*
X524442Y667978D01*
Y697942D01*
X507830Y714554D01*
Y718435D01*
X497062Y729203D01*
X454889D01*
X450410Y733682D01*
G01X480620Y734244D02*
X480530D01*
X476739Y730453D01*
X456084D01*
X451130Y735407D01*
X449523D01*
X447680Y733564D01*
G01X672660Y441007D02*
X660838D01*
X653019Y433188D01*
X626043D01*
X619420Y426565D01*
Y421947D01*
X594286Y396813D01*
X594140D01*
X593130Y395803D01*
Y395657D01*
X566924Y369451D01*
X524532D01*
X511080Y355999D01*
X500150D01*
X464810Y320659D01*
Y311253D01*
G01X470090Y332824D02*
X471441D01*
X512802Y374185D01*
X558335D01*
X620338Y436188D01*
X648258D01*
X658680Y446610D01*
G01X653360Y446280D02*
X644320Y437240D01*
X619905D01*
X558465Y375800D01*
X511940D01*
X475190Y339050D01*
Y339013D01*
G01X517222Y673917D02*
X520672Y677367D01*
Y696395D01*
X503950Y713117D01*
Y717005D01*
X495681Y725274D01*
X476470D01*
X473995Y722799D01*
X471785D01*
X470550Y724034D01*
G01X639350Y250123D02*
X636723D01*
X620352Y233752D01*
X559780D01*
X552770Y226742D01*
X548200D01*
X546025Y228917D01*
X539304D01*
X532835Y222448D01*
X495048D01*
X487168Y214568D01*
G01X480830Y333921D02*
X500958Y354049D01*
X511895D01*
X512589Y354743D01*
X579788D01*
G01X590999Y77041D02*
X585040Y83000D01*
Y106193D01*
X566750Y124483D01*
Y178680D01*
X560310Y185120D01*
X513015D01*
X505580Y192555D01*
G01X497818Y440265D02*
Y438463D01*
X496513Y437158D01*
Y417110D01*
X498995Y414628D01*
X539477D01*
X553260Y428411D01*
Y428416D01*
X559054D01*
X578830Y448192D01*
G01X613730Y717663D02*
X606339D01*
X602099Y713423D01*
X597420D01*
X594180Y710183D01*
Y706785D01*
X596135Y704830D01*
Y699762D01*
X594140Y697767D01*
Y674425D01*
X588080Y668365D01*
Y662512D01*
X586221Y660653D01*
X584522D01*
X577738Y653869D01*
X573122D01*
X568053Y648800D01*
X555100D01*
X550719Y644419D01*
X524485D01*
X523194Y645710D01*
X511406D01*
X508822Y643126D01*
X506363D01*
X505780Y642543D01*
G01X509855Y724107D02*
X511593Y725845D01*
X515616D01*
X516628Y724833D01*
Y721763D01*
X525408Y712983D01*
Y704734D01*
X529525Y700617D01*
Y669349D01*
G01X549314Y647594D02*
X546328Y650580D01*
Y653648D01*
X542928Y657048D01*
Y691171D01*
X540257Y693842D01*
Y698753D01*
X533120Y705890D01*
Y717742D01*
X530115Y720747D01*
Y725509D01*
X528479Y727145D01*
Y733049D01*
X526402Y735126D01*
X521434D01*
X520264Y733956D01*
X516222D01*
X515322Y734856D01*
X512887D01*
X511733Y733702D01*
X507808D01*
X503200Y729094D01*
X500260D01*
G01X563840Y653515D02*
X553236Y664119D01*
Y710961D01*
X547006Y717191D01*
X541684D01*
X537751Y721124D01*
Y732422D01*
X535972Y734201D01*
Y736636D01*
X533294Y739314D01*
X509677D01*
X503366Y733003D01*
X501604D01*
G01X514500Y194300D02*
X515677D01*
X523487Y186490D01*
X561280D01*
X568270Y179500D01*
Y125259D01*
X586810Y106719D01*
Y89104D01*
X590999Y84915D01*
G01X615657Y77041D02*
X606370Y86328D01*
Y96306D01*
X594209Y108467D01*
X587753D01*
X569980Y126240D01*
Y180731D01*
X562656Y188055D01*
X528943D01*
X525293Y191705D01*
G01X521800Y732667D02*
Y725006D01*
X521645Y724851D01*
Y721357D01*
X528213Y714789D01*
Y707121D01*
X537058Y698276D01*
Y664544D01*
X527398Y654884D01*
X525714D01*
X525692Y654862D01*
G01X521516Y650576D02*
X526223Y645869D01*
X550029D01*
X551168Y647008D01*
Y648736D01*
X547909Y651995D01*
Y654073D01*
X544178Y657804D01*
Y691689D01*
X541940Y693927D01*
Y709458D01*
X538334Y713064D01*
Y714971D01*
X533610Y719695D01*
Y727717D01*
X531020Y730307D01*
Y733142D01*
X531029D01*
G01X514420Y733131D02*
Y731377D01*
X520395Y725401D01*
Y720833D01*
X526938Y714290D01*
Y705227D01*
X535314Y696851D01*
Y667342D01*
X529899Y661927D01*
Y661020D01*
G01X524576Y733227D02*
Y727901D01*
X525930Y726547D01*
Y719040D01*
X531808Y713162D01*
Y705432D01*
X538618Y698622D01*
Y693713D01*
X539734Y692597D01*
Y675020D01*
G01X516940Y735683D02*
X517002D01*
X518881Y737562D01*
X532903D01*
X534706Y735759D01*
Y732570D01*
X536484Y730792D01*
Y720606D01*
X541201Y715889D01*
X546540D01*
X551781Y710648D01*
Y703323D01*
X549343Y700885D01*
Y660864D01*
X559440Y650767D01*
G01X615657Y84915D02*
X608430Y92142D01*
Y96446D01*
X595022Y109854D01*
X588603D01*
X571640Y126817D01*
Y181371D01*
X563684Y189327D01*
X530173D01*
X526443Y193057D01*
Y194116D01*
G01X532479Y633588D02*
X536231Y637340D01*
X545160D01*
X547200Y635300D01*
X589400D01*
X612257Y658157D01*
X615300D01*
X615700Y657757D01*
G01X539577Y721891D02*
X540929D01*
X543888Y718932D01*
X547316D01*
X556884Y709364D01*
Y703037D01*
X559813Y700108D01*
Y690488D01*
X563393Y686908D01*
G01X532940Y734810D02*
Y731124D01*
X535194Y728870D01*
Y720128D01*
X541068Y714254D01*
X542166D01*
X546811Y709609D01*
Y704738D01*
X543190Y701117D01*
Y694445D01*
X545428Y692207D01*
Y661062D01*
X551230Y655260D01*
Y652844D01*
G01X548470Y378127D02*
X558682D01*
X619169Y438614D01*
X639088D01*
X647280Y446806D01*
Y446851D01*
G01X544934Y720820D02*
X546913D01*
X558242Y709491D01*
Y704017D01*
X566893Y695366D01*
Y683899D01*
X565568Y682574D01*
X564023D01*
X563586Y682137D01*
G01X544082Y724460D02*
Y724163D01*
X546013Y722232D01*
X547709D01*
X550474Y719467D01*
X554170D01*
X559281Y714356D01*
Y712005D01*
X565168Y706118D01*
Y699614D01*
G01Y679614D02*
X569940Y684386D01*
Y706241D01*
X565127Y711054D01*
X562500D01*
X560533Y713021D01*
Y714677D01*
X550798Y724412D01*
X549049D01*
G01X555551Y722342D02*
X558733D01*
X573286Y707789D01*
Y670984D01*
X576520Y667750D01*
G01X622290Y708516D02*
Y705440D01*
X618575Y701725D01*
X617305D01*
X614536Y698956D01*
Y676056D01*
X611540Y673060D01*
Y669004D01*
X609170Y666634D01*
Y665382D01*
X590587Y646799D01*
X571790D01*
G01X566950Y659439D02*
X569416Y661905D01*
X578194D01*
X578195Y661904D01*
X581498D01*
X582370Y662776D01*
Y666916D01*
X585280Y669826D01*
Y673208D01*
X591225Y679153D01*
Y708771D01*
X579220Y720776D01*
G01X569604Y721248D02*
X573944D01*
X582170Y713022D01*
Y685978D01*
X582955Y685193D01*
Y681902D01*
X582690Y681637D01*
Y670777D01*
X576078Y664165D01*
X568440D01*
X563850Y659575D01*
G01X563441Y676872D02*
X566505D01*
X571307Y681674D01*
Y707366D01*
X560582Y718091D01*
X560544D01*
G01X557978Y734053D02*
Y732469D01*
X560050Y730397D01*
Y723079D01*
X563516Y719613D01*
X566803D01*
X574717Y711699D01*
Y673962D01*
X579076Y669603D01*
G01X580637Y663629D02*
Y666951D01*
X584030Y670344D01*
Y677678D01*
X587790Y681438D01*
Y683297D01*
X583630Y687457D01*
Y702663D01*
X586130Y705163D01*
Y711426D01*
X575880Y721676D01*
Y725390D01*
X571232Y730038D01*
Y732545D01*
G01X615690Y625536D02*
X593435D01*
X585085Y617186D01*
Y589797D01*
X594162Y580720D01*
Y547365D01*
X583890Y537093D01*
G01X577217Y652002D02*
X578848Y650371D01*
X584324D01*
X589220Y655267D01*
Y659553D01*
X590780Y661113D01*
Y666316D01*
X597420Y672956D01*
Y695464D01*
X599020Y697064D01*
Y706205D01*
X600650Y707835D01*
G01X595950Y708997D02*
Y707071D01*
X597585Y705436D01*
Y698910D01*
X596170Y697495D01*
Y673831D01*
X589530Y667191D01*
Y661911D01*
X586822Y659203D01*
X586657D01*
X580740Y653286D01*
G01X576987Y660180D02*
X581741D01*
X583664Y662103D01*
X585620D01*
X586628Y663111D01*
Y668964D01*
X592690Y675026D01*
Y698368D01*
X594685Y700363D01*
Y704011D01*
X592607Y706089D01*
Y712324D01*
X580510Y724421D01*
G01X574190Y717805D02*
X580920Y711075D01*
Y684645D01*
X581705Y683860D01*
Y682425D01*
X578842Y679562D01*
X576644D01*
G01X698683Y487517D02*
X709870Y498704D01*
Y510446D01*
X701637Y518679D01*
X695228D01*
X693508Y516959D01*
X673543D01*
X672047Y518455D01*
X638616D01*
X633667Y513506D01*
X631993D01*
X603819Y485332D01*
G01X596998Y658008D02*
X597335Y658345D01*
X599343D01*
X607720Y666722D01*
Y667235D01*
X608810Y668325D01*
Y698674D01*
X609825Y699689D01*
X610055D01*
X622210Y711844D01*
X648792D01*
X654050Y717102D01*
Y718086D01*
G01X591840Y659568D02*
X595140Y662868D01*
Y668908D01*
X598670Y672438D01*
Y694603D01*
X600270Y696203D01*
Y704315D01*
X608763Y712808D01*
X609031D01*
X609840Y713617D01*
G01X602332Y671156D02*
Y671169D01*
X603745Y672582D01*
Y679876D01*
X602495Y681126D01*
Y704489D01*
X605291Y707285D01*
X608166D01*
X608975Y708094D01*
G01X612914Y707630D02*
X608130Y702846D01*
X606064D01*
X604205Y700987D01*
Y698350D01*
X605195Y697360D01*
Y671579D01*
X602041Y668425D01*
X600736D01*
G01X620830Y717516D02*
X614640Y711326D01*
Y706916D01*
X609120Y701396D01*
X606665D01*
X605655Y700386D01*
Y698951D01*
X606645Y697961D01*
Y667928D01*
X606470Y667753D01*
Y667240D01*
X601973Y662743D01*
X597685D01*
X597300Y663128D01*
G01X603938Y753623D02*
X607226Y750335D01*
X627014D01*
X628356Y751677D01*
X633488D01*
X638635Y746530D01*
Y740055D01*
X638203Y739623D01*
Y738187D01*
X638890Y737500D01*
Y734879D01*
G01X617980Y460408D02*
Y464460D01*
X627573Y474053D01*
X672561D01*
X680028Y481520D01*
X703620D01*
X705823Y483723D01*
X706734D01*
G01X626250Y450248D02*
X629177Y453175D01*
X637488D01*
X641350Y449313D01*
X660700D01*
X666006Y444007D01*
X673912D01*
X674824Y443095D01*
X700793D01*
X703830Y446132D01*
X710590D01*
X717792Y453334D01*
X728050D01*
X730300Y455584D01*
X735551D01*
X739075Y459108D01*
Y462302D01*
X737350Y464026D01*
Y464330D01*
G01X622100Y465822D02*
Y463129D01*
X626718Y458511D01*
X637811D01*
X645959Y450363D01*
X664336D01*
X667587Y447112D01*
X703146D01*
X713396Y457362D01*
X734889D01*
X737350Y459823D01*
G01X625900Y461769D02*
X631958D01*
X633564Y460163D01*
X637653D01*
X646403Y451413D01*
X664776D01*
X668027Y448162D01*
X701742D01*
X712912Y459332D01*
X715528D01*
G01X636010Y469995D02*
X641499Y464506D01*
Y462379D01*
X651387Y452491D01*
X678844D01*
X679510Y453157D01*
X705245D01*
X713145Y461057D01*
X722116D01*
X726430Y465371D01*
G01X628250Y471142D02*
X634399D01*
X635202Y471945D01*
X640123D01*
X644470Y467598D01*
X662609D01*
X666952Y471941D01*
X683113D01*
G01X651840Y460012D02*
X652485Y460657D01*
X678970D01*
X679121Y460808D01*
X693056D01*
X698260Y466012D01*
X703225D01*
X706734Y469521D01*
Y471913D01*
G01X720140Y478333D02*
X703481Y461674D01*
X701623D01*
X698806Y458858D01*
X679935D01*
X676568Y455491D01*
X667932D01*
X666910Y456513D01*
X665567Y457851D01*
X648920D01*
G01X706734Y475850D02*
X699946D01*
X694570Y470474D01*
Y465118D01*
X691310Y461858D01*
X678070D01*
X677919Y461707D01*
X654119D01*
X653130Y462696D01*
X647475D01*
X646600Y463571D01*
G01X719370Y472436D02*
X705192Y458258D01*
X701570D01*
X697519Y454207D01*
X679070D01*
X678404Y453541D01*
X667122D01*
X665425Y455238D01*
X651080D01*
G01X692520Y506898D02*
X684732Y499110D01*
X684160D01*
X684140Y499090D01*
X657130D01*
X652377Y494337D01*
X650150D01*
G01X642999Y685781D02*
Y687685D01*
X656505Y701191D01*
G01X638470Y762212D02*
X643155Y757527D01*
X649640D01*
G54D16*
X712975Y155655D03*
Y234461D03*
X723275Y155655D03*
Y234461D03*
G54D26*
G01X174151Y232011D02*
X174223Y232083D01*
X174577D01*
X180670Y238176D01*
X184770D01*
X186070Y239476D01*
Y244182D01*
X190196Y248308D01*
Y249023D01*
X196516Y255343D01*
Y260123D01*
X196288Y260351D01*
X195847D01*
X194693Y259197D01*
G01X175071Y231091D02*
X175143Y231163D01*
Y231517D01*
X181002Y237376D01*
X185102D01*
X186870Y239144D01*
Y243850D01*
X190996Y247976D01*
Y248691D01*
X197316Y255011D01*
Y260455D01*
X196620Y261151D01*
X195739D01*
X194693Y262197D01*
G01X205883Y225960D02*
X205955Y226032D01*
X206300D01*
X209100Y228832D01*
Y232834D01*
X208540Y233394D01*
Y246811D01*
X212116Y250387D01*
Y252614D01*
X214160Y254658D01*
Y257100D01*
X212916Y258344D01*
Y263137D01*
X214062Y264283D01*
X215253D01*
X216109Y265139D01*
G01X206803Y225040D02*
X206875Y225112D01*
Y225466D01*
X206870D01*
X209900Y228496D01*
Y233166D01*
X209340Y233726D01*
Y246479D01*
X212916Y250055D01*
Y252282D01*
X214960Y254326D01*
Y257432D01*
X213716Y258676D01*
Y262805D01*
X214394Y263483D01*
X215780D01*
X216109Y263154D01*
Y262139D01*
G01X243930Y230680D02*
Y230782D01*
X243680Y231032D01*
Y233454D01*
X247150Y236924D01*
Y243336D01*
X255410Y251596D01*
Y252281D01*
X259804Y256675D01*
Y260191D01*
X258603Y261392D01*
X257716D01*
X256916Y262192D01*
Y262609D01*
G01X257253Y259197D02*
Y260096D01*
X257749Y260592D01*
X258271D01*
X259004Y259859D01*
Y257007D01*
X254610Y252613D01*
Y251928D01*
X246350Y243668D01*
Y237256D01*
X242880Y233786D01*
Y231032D01*
X242630Y230782D01*
Y230680D01*
G01X269192Y248209D02*
X269195Y248206D01*
X273873D01*
X275910Y246169D01*
Y243348D01*
X277234Y242024D01*
X280779D01*
X282316Y240487D01*
Y235914D01*
X279080Y232678D01*
Y230601D01*
X279330Y230351D01*
Y230249D01*
G01X272242Y244842D02*
X271449Y245635D01*
Y246870D01*
X271985Y247406D01*
X273541D01*
X275110Y245837D01*
Y243016D01*
X276902Y241224D01*
X280447D01*
X281516Y240155D01*
Y236246D01*
X278280Y233010D01*
Y230601D01*
X278030Y230351D01*
Y230249D01*
G01X300310Y253842D02*
Y255185D01*
X300735Y255610D01*
X301408D01*
X302166Y254852D01*
Y249080D01*
X301916Y248830D01*
Y248778D01*
G01X300310Y257242D02*
X300308Y257240D01*
Y256788D01*
X300686Y256410D01*
X301740D01*
X302966Y255184D01*
Y249080D01*
X303216Y248830D01*
Y248778D01*
G01X305132Y286867D02*
X304581D01*
X304030Y286316D01*
Y284756D01*
X309244Y279542D01*
X312504D01*
X312717Y279755D01*
G01X301732Y286867D02*
X302714D01*
X303230Y286351D01*
Y284424D01*
X308912Y278742D01*
X312378D01*
X312665Y278455D01*
X312717D01*
G54D17*
G01X135050Y53493D02*
X137531Y55974D01*
X138629D01*
X139730Y57075D01*
Y60422D01*
X148236Y68928D01*
X169480D01*
X173629Y73077D01*
X255317D01*
X260321Y68073D01*
X359393D01*
X363713Y72393D01*
X373168D01*
X381318Y80543D01*
X408210D01*
X423790Y96123D01*
Y115775D01*
X428750Y120735D01*
Y223296D01*
X425343Y226703D01*
X423340D01*
X421640Y228403D01*
G01X137540Y58255D02*
Y60495D01*
X147573Y70528D01*
X168817D01*
X172966Y74677D01*
X255983D01*
X260987Y69673D01*
X358730D01*
X363050Y73993D01*
X372505D01*
X380655Y82143D01*
X407543D01*
X422190Y96790D01*
Y116438D01*
X427150Y121398D01*
Y222633D01*
X424680Y225103D01*
X423340D01*
X421640Y223403D01*
G01X709500Y736800D02*
X706700D01*
X699200Y744300D01*
X686700D01*
X667400Y725000D01*
Y705800D01*
X648500Y686900D01*
Y685300D01*
X629800Y666600D01*
X621600D01*
X614500Y659500D01*
X611000D01*
X591200Y639700D01*
X570500D01*
X569600Y640600D01*
X555200D01*
X554300Y639700D01*
X517413D01*
X514113Y636400D01*
X501400D01*
X498800Y633800D01*
Y632600D01*
X497700Y631500D01*
X494900D01*
X486700Y639700D01*
X477800D01*
X474000Y643500D01*
X464700D01*
X462200Y641000D01*
X453400D01*
X451400Y643000D01*
X441726D01*
X437926Y639200D01*
X424600D01*
X419100Y644700D01*
X406306D01*
X403970Y642364D01*
G54D27*
G01X231710Y243642D02*
X233181Y245113D01*
Y245838D01*
X229528Y249491D01*
Y254201D01*
X231028Y255701D01*
X235200D01*
X236537Y257038D01*
Y259623D01*
X235463Y260697D01*
X233793D01*
G01X239569Y260639D02*
X238165D01*
X237707Y260181D01*
Y256553D01*
X235685Y254531D01*
X231513D01*
X230698Y253716D01*
Y249976D01*
X234008Y246666D01*
X234013Y246671D01*
X234413Y246271D01*
Y242945D01*
X231710Y240242D01*
G54D18*
G01X352693Y32138D02*
X439186D01*
X459984Y52936D01*
X465620D01*
X470500Y57816D01*
Y64466D01*
X478120Y72086D01*
Y111531D01*
X482900Y116311D01*
X485513D01*
X485570Y116254D01*
X494610D01*
X500930Y122574D01*
Y125817D01*
X499456Y127291D01*
Y128666D01*
G54D19*
G01X490600Y608136D02*
X492636Y606100D01*
X511400D01*
X516400Y611100D01*
X519500D01*
X526850Y618450D01*
X536950D01*
X538400Y617000D01*
X558800D01*
X574600Y632800D01*
X593000D01*
X597050Y636850D01*
X609850D01*
X624120Y651120D01*
X645320D01*
X646600Y652400D01*
X655000D01*
X657000Y650400D01*
X706000D01*
X721100Y665500D01*
Y689400D01*
G01X731200Y716200D02*
X735200Y712200D01*
Y673700D01*
X708200Y646700D01*
X645900D01*
X643800Y644600D01*
X621100D01*
X609800Y633300D01*
X597900D01*
X591650Y627050D01*
X587550D01*
X570652Y610152D01*
X530648D01*
X526896Y606400D01*
X520200D01*
X515800Y602000D01*
X513000D01*
X511600Y603400D01*
X493000D01*
X489800Y600200D01*
M02*
